FILE_TYPE = MACRO_DRAWING;
SET COLOR_WIRE YELLOW;
SET COLOR_PROP ORANGE;
SET COLOR_DOT WHITE;
SET COLOR_ARC YELLOW;
SET COLOR_BODY GREEN;
SET COLOR_NOTE PURPLE;
SET PROP_DISPLAY VALUE;
SET PAGE_NUMBER P176;
FORCEADD OFFPAGE..5
(-1950 3175);
FORCEPROP 2 LAST $XR1 205 
J 0
(-2325 3175);
DISPLAY 0.638298 (-2325 3175);
PAINT MONO (-2325 3175);
FORCEPROP 2 LAST $XR0 204 
J 0
(-2205 3175);
DISPLAY 0.638298 (-2205 3175);
PAINT MONO (-2205 3175);
FORCEPROP 2 LAST CDS_LIB standard
J 0
(-1950 3175);
PAINT MONO (-1950 3175);
DISPLAY INVISIBLE (-1950 3175);
FORCEPROP 1 LAST OFFPAGE TRUE
J 0
(-1625 3050);
DISPLAY 0.872340 (-1625 3050);
DISPLAY INVISIBLE (-1625 3050);
FORCEPROP 1 LAST COMMENT_BODY TRUE
J 0
(-1850 3100);
DISPLAY 1.170213 (-1850 3100);
PAINT GREEN (-1850 3100);
DISPLAY INVISIBLE (-1850 3100);
FORCEPROP 2 LAST PATH I10
J 0
(-1900 3250);
DISPLAY 1.021277 (-1900 3250);
DISPLAY INVISIBLE (-1900 3250);
FORCEADD OFFPAGE..1
(-1950 3225);
FORCEPROP 2 LAST $XR0 213 
J 0
(-2202 3225);
DISPLAY 0.638298 (-2202 3225);
PAINT MONO (-2202 3225);
FORCEPROP 2 LAST CDS_LIB standard
J 0
(-1950 3225);
PAINT MONO (-1950 3225);
DISPLAY INVISIBLE (-1950 3225);
FORCEPROP 1 LAST OFFPAGE TRUE
J 0
(-1625 3100);
DISPLAY 0.872340 (-1625 3100);
DISPLAY INVISIBLE (-1625 3100);
FORCEPROP 1 LAST COMMENT_BODY TRUE
J 0
(-1825 3125);
DISPLAY 1.170213 (-1825 3125);
PAINT GREEN (-1825 3125);
DISPLAY INVISIBLE (-1825 3125);
FORCEPROP 2 LAST PATH I11
J 0
(-1900 3300);
DISPLAY 1.021277 (-1900 3300);
DISPLAY INVISIBLE (-1900 3300);
FORCEADD OFFPAGE..1
R 2
(4750 1875);
FORCEPROP 2 LAST $XR0 195 
J 0
(4936 1875);
DISPLAY 0.638298 (4936 1875);
PAINT MONO (4936 1875);
FORCEPROP 2 LAST CDS_LIB standard
J 0
(4750 1875);
DISPLAY INVISIBLE (4750 1875);
FORCEPROP 1 LAST OFFPAGE TRUE
J 2
(4425 1750);
DISPLAY 1.170213 (4425 1750);
PAINT GREEN (4425 1750);
DISPLAY INVISIBLE (4425 1750);
FORCEPROP 1 LAST COMMENT_BODY TRUE
J 2
(4625 1775);
DISPLAY 1.170213 (4625 1775);
PAINT GREEN (4625 1775);
DISPLAY INVISIBLE (4625 1775);
FORCEPROP 2 LAST PATH I118
J 0
(4950 1925);
DISPLAY 1.021277 (4950 1925);
DISPLAY INVISIBLE (4950 1925);
FORCEADD OFFPAGE..1
R 2
(4750 1925);
FORCEPROP 2 LAST $XR0 195 
J 0
(4936 1925);
DISPLAY 0.638298 (4936 1925);
PAINT MONO (4936 1925);
FORCEPROP 2 LAST CDS_LIB standard
J 0
(4750 1925);
DISPLAY INVISIBLE (4750 1925);
FORCEPROP 1 LAST OFFPAGE TRUE
J 2
(4425 1800);
DISPLAY 1.170213 (4425 1800);
PAINT GREEN (4425 1800);
DISPLAY INVISIBLE (4425 1800);
FORCEPROP 1 LAST COMMENT_BODY TRUE
J 2
(4625 1825);
DISPLAY 1.170213 (4625 1825);
PAINT GREEN (4625 1825);
DISPLAY INVISIBLE (4625 1825);
FORCEPROP 2 LAST PATH I119
J 0
(4950 1975);
DISPLAY 1.021277 (4950 1975);
DISPLAY INVISIBLE (4950 1975);
FORCEADD OFFPAGE..1
(-1950 3125);
FORCEPROP 2 LAST $XR1 215 
J 0
(-2322 3125);
DISPLAY 0.638298 (-2322 3125);
PAINT MONO (-2322 3125);
FORCEPROP 2 LAST $XR0 204 
J 0
(-2202 3125);
DISPLAY 0.638298 (-2202 3125);
PAINT MONO (-2202 3125);
FORCEPROP 2 LAST CDS_LIB standard
J 0
(-1950 3125);
DISPLAY INVISIBLE (-1950 3125);
FORCEPROP 1 LAST OFFPAGE TRUE
J 0
(-1625 3000);
DISPLAY 0.872340 (-1625 3000);
DISPLAY INVISIBLE (-1625 3000);
FORCEPROP 1 LAST COMMENT_BODY TRUE
J 0
(-1825 3025);
DISPLAY 1.170213 (-1825 3025);
PAINT GREEN (-1825 3025);
DISPLAY INVISIBLE (-1825 3025);
FORCEPROP 2 LAST PATH I155
J 0
(-2250 3175);
DISPLAY 1.021277 (-2250 3175);
DISPLAY INVISIBLE (-2250 3175);
FORCEADD OFFPAGE..1
(-1950 2575);
FORCEPROP 2 LAST $XR0 184 
J 0
(-2202 2575);
DISPLAY 0.638298 (-2202 2575);
PAINT MONO (-2202 2575);
FORCEPROP 2 LAST CDS_LIB standard
J 0
(-1950 2575);
PAINT MONO (-1950 2575);
DISPLAY INVISIBLE (-1950 2575);
FORCEPROP 1 LAST OFFPAGE TRUE
J 0
(-1625 2450);
DISPLAY 0.872340 (-1625 2450);
DISPLAY INVISIBLE (-1625 2450);
FORCEPROP 1 LAST COMMENT_BODY TRUE
J 0
(-1825 2475);
DISPLAY 1.170213 (-1825 2475);
PAINT GREEN (-1825 2475);
DISPLAY INVISIBLE (-1825 2475);
FORCEPROP 2 LAST PATH I156
J 0
(-2250 2625);
DISPLAY 1.021277 (-2250 2625);
DISPLAY INVISIBLE (-2250 2625);
FORCEADD OFFPAGE..1
(-1950 2625);
FORCEPROP 2 LAST $XR1 190 
J 0
(-2322 2625);
DISPLAY 0.638298 (-2322 2625);
PAINT MONO (-2322 2625);
FORCEPROP 2 LAST $XR0 184 
J 0
(-2202 2625);
DISPLAY 0.638298 (-2202 2625);
PAINT MONO (-2202 2625);
FORCEPROP 2 LAST CDS_LIB standard
J 0
(-1950 2625);
PAINT MONO (-1950 2625);
DISPLAY INVISIBLE (-1950 2625);
FORCEPROP 1 LAST OFFPAGE TRUE
J 0
(-1625 2500);
DISPLAY 0.872340 (-1625 2500);
DISPLAY INVISIBLE (-1625 2500);
FORCEPROP 1 LAST COMMENT_BODY TRUE
J 0
(-1825 2525);
DISPLAY 1.170213 (-1825 2525);
PAINT GREEN (-1825 2525);
DISPLAY INVISIBLE (-1825 2525);
FORCEPROP 2 LAST PATH I157
J 0
(-2250 2675);
DISPLAY 1.021277 (-2250 2675);
DISPLAY INVISIBLE (-2250 2675);
FORCEADD OFFPAGE..1
(-1950 1875);
FORCEPROP 2 LAST $XR0 199 
J 0
(-2202 1875);
DISPLAY 0.638298 (-2202 1875);
PAINT MONO (-2202 1875);
FORCEPROP 2 LAST CDS_LIB standard
J 0
(-1950 1875);
PAINT MONO (-1950 1875);
DISPLAY INVISIBLE (-1950 1875);
FORCEPROP 1 LAST OFFPAGE TRUE
J 0
(-1625 1750);
DISPLAY 0.872340 (-1625 1750);
DISPLAY INVISIBLE (-1625 1750);
FORCEPROP 1 LAST COMMENT_BODY TRUE
J 0
(-1825 1775);
DISPLAY 1.170213 (-1825 1775);
PAINT GREEN (-1825 1775);
DISPLAY INVISIBLE (-1825 1775);
FORCEPROP 2 LAST PATH I16
J 0
(-1900 1950);
DISPLAY 1.021277 (-1900 1950);
DISPLAY INVISIBLE (-1900 1950);
FORCEADD UNIVERSAL_GND..1
(-2475 -75);
FORCEPROP 3 LASTPIN (-2475 -25) SIG_NAME GND\g
J 0
(-2465 -15);
DISPLAY 0.659574 (-2465 -15);
PAINT MONO (-2465 -15);
DISPLAY INVISIBLE (-2465 -15);
FORCEPROP 2 LAST CDS_LIB logical_power
J 0
(-2475 -75);
PAINT MONO (-2475 -75);
DISPLAY INVISIBLE (-2475 -75);
FORCEPROP 1 LAST HDL_POWER GND
J 1
(-2450 -150);
DISPLAY 0.872340 (-2450 -150);
PAINT GREEN (-2450 -150);
DISPLAY INVISIBLE (-2450 -150);
FORCEPROP 1 LAST PATH I161
J 0
(-2400 -75);
DISPLAY 0.872340 (-2400 -75);
PAINT AQUA (-2400 -75);
DISPLAY INVISIBLE (-2400 -75);
FORCEPROP 2 LAST ROOM IO_SLOT
J 1
(-2700 0);
DISPLAY 0.744681 (-2700 0);
DISPLAY INVISIBLE (-2700 0);
FORCEADD UNIVERSAL_GND..1
(-2200 -75);
FORCEPROP 3 LASTPIN (-2200 -25) SIG_NAME GND\g
J 0
(-2190 -15);
DISPLAY 0.659574 (-2190 -15);
PAINT MONO (-2190 -15);
DISPLAY INVISIBLE (-2190 -15);
FORCEPROP 2 LAST CDS_LIB logical_power
J 0
(-2200 -75);
PAINT MONO (-2200 -75);
DISPLAY INVISIBLE (-2200 -75);
FORCEPROP 1 LAST HDL_POWER GND
J 1
(-2175 -150);
DISPLAY 0.872340 (-2175 -150);
PAINT GREEN (-2175 -150);
DISPLAY INVISIBLE (-2175 -150);
FORCEPROP 1 LAST PATH I163
J 0
(-2125 -75);
DISPLAY 0.872340 (-2125 -75);
PAINT AQUA (-2125 -75);
DISPLAY INVISIBLE (-2125 -75);
FORCEPROP 2 LAST ROOM IO_SLOT
J 1
(-2425 0);
DISPLAY 0.744681 (-2425 0);
DISPLAY INVISIBLE (-2425 0);
FORCEADD UNIVERSAL_POWER..1
(-2475 1175);
FORCEPROP 3 LASTPIN (-2475 1125) SIG_NAME P3V3_AUX\g
J 0
(-2465 1135);
DISPLAY 0.659574 (-2465 1135);
PAINT MONO (-2465 1135);
DISPLAY INVISIBLE (-2465 1135);
FORCEPROP 1 LAST HDL_POWER P3V3_AUX
J 1
(-2475 1225);
DISPLAY 0.872340 (-2475 1225);
PAINT GREEN (-2475 1225);
FORCEPROP 2 LAST CDS_LIB logical_power
J 0
(-2475 1175);
PAINT MONO (-2475 1175);
DISPLAY INVISIBLE (-2475 1175);
FORCEPROP 1 LAST PATH I168
J 0
(-2425 1200);
DISPLAY 0.872340 (-2425 1200);
PAINT AQUA (-2425 1200);
DISPLAY INVISIBLE (-2425 1200);
FORCEADD OFFPAGE..1
(-1950 1825);
FORCEPROP 2 LAST $XR0 199 
J 0
(-2202 1825);
DISPLAY 0.638298 (-2202 1825);
PAINT MONO (-2202 1825);
FORCEPROP 2 LAST CDS_LIB standard
J 0
(-1950 1825);
PAINT MONO (-1950 1825);
DISPLAY INVISIBLE (-1950 1825);
FORCEPROP 1 LAST OFFPAGE TRUE
J 0
(-1625 1700);
DISPLAY 0.872340 (-1625 1700);
DISPLAY INVISIBLE (-1625 1700);
FORCEPROP 1 LAST COMMENT_BODY TRUE
J 0
(-1825 1725);
DISPLAY 1.170213 (-1825 1725);
PAINT GREEN (-1825 1725);
DISPLAY INVISIBLE (-1825 1725);
FORCEPROP 2 LAST PATH I17
J 0
(-1900 1900);
DISPLAY 1.021277 (-1900 1900);
DISPLAY INVISIBLE (-1900 1900);
FORCEADD OFFPAGE..2
(-800 450);
FORCEPROP 2 LAST $XR0 184 
J 0
(-611 450);
DISPLAY 0.638298 (-611 450);
PAINT MONO (-611 450);
FORCEPROP 2 LAST CDS_LIB standard
J 0
(-800 450);
PAINT MONO (-800 450);
DISPLAY INVISIBLE (-800 450);
FORCEPROP 1 LAST OFFPAGE TRUE
J 0
(-475 325);
DISPLAY 0.872340 (-475 325);
DISPLAY INVISIBLE (-475 325);
FORCEPROP 1 LAST COMMENT_BODY TRUE
J 0
(-845 355);
DISPLAY 0.872340 (-845 355);
PAINT GREEN (-845 355);
DISPLAY INVISIBLE (-845 355);
FORCEPROP 2 LAST PATH I171
J 0
(-600 500);
DISPLAY 1.021277 (-600 500);
DISPLAY INVISIBLE (-600 500);
FORCEADD OFFPAGE..2
(-800 525);
FORCEPROP 2 LAST $XR1 184 
J 0
(-491 525);
DISPLAY 0.638298 (-491 525);
PAINT MONO (-491 525);
FORCEPROP 2 LAST $XR0 190 
J 0
(-611 525);
DISPLAY 0.638298 (-611 525);
PAINT MONO (-611 525);
FORCEPROP 2 LAST CDS_LIB standard
J 0
(-800 525);
PAINT MONO (-800 525);
DISPLAY INVISIBLE (-800 525);
FORCEPROP 1 LAST OFFPAGE TRUE
J 0
(-475 400);
DISPLAY 0.872340 (-475 400);
DISPLAY INVISIBLE (-475 400);
FORCEPROP 1 LAST COMMENT_BODY TRUE
J 0
(-845 430);
DISPLAY 0.872340 (-845 430);
PAINT GREEN (-845 430);
DISPLAY INVISIBLE (-845 430);
FORCEPROP 2 LAST PATH I172
J 0
(-600 575);
DISPLAY 1.021277 (-600 575);
DISPLAY INVISIBLE (-600 575);
FORCEADD Q_RES..2
(-2475 800);
FORCEPROP 1 LAST PART_NUMBER CS31002FB08
J 0
(-2435 675);
DISPLAY 0.510638 (-2435 675);
DISPLAY INVISIBLE (-2435 675);
FORCEPROP 1 LAST WATTAGE 1/16W
J 0
(-2435 775);
DISPLAY 0.638298 (-2435 775);
FORCEPROP 1 LAST TOLERANCE 1%
J 0
(-2430 825);
DISPLAY 0.638298 (-2430 825);
FORCEPROP 1 LAST PACK_TYPE 0402LF
J 0
(-2435 675);
DISPLAY 0.638298 (-2435 675);
FORCEPROP 1 LAST VALUE 10K
J 0
(-2430 875);
DISPLAY 0.638298 (-2430 875);
FORCEPROP 1 LAST MATERIAL EMPTY
J 0
(-2435 725);
DISPLAY 0.638298 (-2435 725);
PAINT RED (-2435 725);
FORCEPROP 1 LAST $LOCATION R2508
J 0
(-2430 925);
DISPLAY 0.978723 (-2430 925);
FORCEPROP 1 LASTPIN (-2475 900) $PN 1
J 0
(-2470 862);
DISPLAY 0.787234 (-2470 862);
PAINT MONO (-2470 862);
FORCEPROP 1 LASTPIN (-2475 700) $PN 2
J 0
(-2470 710);
DISPLAY 0.787234 (-2470 710);
PAINT MONO (-2470 710);
FORCEPROP 2 LAST CDS_LIB pure_quanta
J 0
(-2475 800);
DISPLAY INVISIBLE (-2475 800);
FORCEPROP 1 LAST PATH I173
J 0
(-2425 975);
DISPLAY 0.978723 (-2425 975);
PAINT WHITE (-2425 975);
DISPLAY INVISIBLE (-2425 975);
FORCEPROP 0 LAST CDS_LOCATION R2508
J 0
(-2425 975);
DISPLAY 1.021277 (-2425 975);
DISPLAY INVISIBLE (-2425 975);
FORCEPROP 0 LAST $SEC 1
J 0
(-2425 975);
DISPLAY 0.680851 (-2425 975);
PAINT MONO (-2425 975);
DISPLAY INVISIBLE (-2425 975);
FORCEPROP 0 LAST CDS_SEC 1
J 0
(-2425 975);
DISPLAY 1.021277 (-2425 975);
DISPLAY INVISIBLE (-2425 975);
FORCEADD Q_RES..2
(-2475 150);
FORCEPROP 1 LAST PART_NUMBER CS21002FB06
J 0
(-2435 25);
DISPLAY 0.510638 (-2435 25);
DISPLAY INVISIBLE (-2435 25);
FORCEPROP 1 LAST WATTAGE 1/16W
J 0
(-2435 125);
DISPLAY 0.638298 (-2435 125);
FORCEPROP 1 LAST VALUE 1K
J 0
(-2430 225);
DISPLAY 0.638298 (-2430 225);
FORCEPROP 1 LAST PACK_TYPE 0402LF
J 0
(-2435 25);
DISPLAY 0.638298 (-2435 25);
FORCEPROP 1 LAST MATERIAL EMPTY
J 0
(-2435 75);
DISPLAY 0.638298 (-2435 75);
PAINT RED (-2435 75);
FORCEPROP 1 LAST TOLERANCE 1%
J 0
(-2430 175);
DISPLAY 0.638298 (-2430 175);
FORCEPROP 1 LAST $LOCATION R2509
J 0
(-2430 275);
DISPLAY 0.978723 (-2430 275);
FORCEPROP 1 LASTPIN (-2475 250) $PN 1
J 0
(-2470 212);
DISPLAY 0.787234 (-2470 212);
PAINT MONO (-2470 212);
FORCEPROP 1 LASTPIN (-2475 50) $PN 2
J 0
(-2470 60);
DISPLAY 0.787234 (-2470 60);
PAINT MONO (-2470 60);
FORCEPROP 2 LAST CDS_LIB pure_quanta
J 0
(-2475 150);
DISPLAY INVISIBLE (-2475 150);
FORCEPROP 1 LAST PATH I174
J 0
(-2425 325);
DISPLAY 0.978723 (-2425 325);
PAINT WHITE (-2425 325);
DISPLAY INVISIBLE (-2425 325);
FORCEPROP 0 LAST CDS_LOCATION R2509
J 0
(-2425 325);
DISPLAY 1.021277 (-2425 325);
DISPLAY INVISIBLE (-2425 325);
FORCEPROP 0 LAST $SEC 1
J 0
(-2425 325);
DISPLAY 0.680851 (-2425 325);
PAINT MONO (-2425 325);
DISPLAY INVISIBLE (-2425 325);
FORCEPROP 0 LAST CDS_SEC 1
J 0
(-2425 325);
DISPLAY 1.021277 (-2425 325);
DISPLAY INVISIBLE (-2425 325);
FORCEADD Q_RES..2
(-2200 800);
FORCEPROP 1 LAST PART_NUMBER CS31002FB08
J 0
(-2160 675);
DISPLAY 0.510638 (-2160 675);
DISPLAY INVISIBLE (-2160 675);
FORCEPROP 1 LAST PACK_TYPE 0402LF
J 0
(-2160 675);
DISPLAY 0.638298 (-2160 675);
FORCEPROP 1 LAST MATERIAL EMPTY
J 0
(-2160 725);
DISPLAY 0.638298 (-2160 725);
PAINT RED (-2160 725);
FORCEPROP 1 LAST WATTAGE 1/16W
J 0
(-2160 775);
DISPLAY 0.638298 (-2160 775);
FORCEPROP 1 LAST VALUE 10K
J 0
(-2155 875);
DISPLAY 0.638298 (-2155 875);
FORCEPROP 1 LAST TOLERANCE 1%
J 0
(-2155 825);
DISPLAY 0.638298 (-2155 825);
FORCEPROP 1 LAST $LOCATION R2510
J 0
(-2155 925);
DISPLAY 0.978723 (-2155 925);
FORCEPROP 1 LASTPIN (-2200 900) $PN 1
J 0
(-2195 862);
DISPLAY 0.787234 (-2195 862);
PAINT MONO (-2195 862);
FORCEPROP 1 LASTPIN (-2200 700) $PN 2
J 0
(-2195 710);
DISPLAY 0.787234 (-2195 710);
PAINT MONO (-2195 710);
FORCEPROP 2 LAST CDS_LIB pure_quanta
J 0
(-2200 800);
DISPLAY INVISIBLE (-2200 800);
FORCEPROP 1 LAST PATH I175
J 0
(-2150 975);
DISPLAY 0.978723 (-2150 975);
PAINT WHITE (-2150 975);
DISPLAY INVISIBLE (-2150 975);
FORCEPROP 0 LAST CDS_LOCATION R2510
J 0
(-2150 975);
DISPLAY 1.021277 (-2150 975);
DISPLAY INVISIBLE (-2150 975);
FORCEPROP 0 LAST $SEC 1
J 0
(-2150 975);
DISPLAY 0.680851 (-2150 975);
PAINT MONO (-2150 975);
DISPLAY INVISIBLE (-2150 975);
FORCEPROP 0 LAST CDS_SEC 1
J 0
(-2150 975);
DISPLAY 1.021277 (-2150 975);
DISPLAY INVISIBLE (-2150 975);
FORCEADD Q_RES..2
(-2200 150);
FORCEPROP 1 LAST PART_NUMBER CS21002FB06
J 0
(-2160 25);
DISPLAY 0.510638 (-2160 25);
DISPLAY INVISIBLE (-2160 25);
FORCEPROP 1 LAST PACK_TYPE 0402LF
J 0
(-2160 25);
DISPLAY 0.638298 (-2160 25);
FORCEPROP 1 LAST MATERIAL EMPTY
J 0
(-2160 75);
DISPLAY 0.638298 (-2160 75);
PAINT RED (-2160 75);
FORCEPROP 1 LAST WATTAGE 1/16W
J 0
(-2160 125);
DISPLAY 0.638298 (-2160 125);
FORCEPROP 1 LAST TOLERANCE 1%
J 0
(-2155 175);
DISPLAY 0.638298 (-2155 175);
FORCEPROP 1 LAST VALUE 1K
J 0
(-2155 225);
DISPLAY 0.638298 (-2155 225);
FORCEPROP 1 LAST $LOCATION R2511
J 0
(-2155 275);
DISPLAY 0.978723 (-2155 275);
FORCEPROP 1 LASTPIN (-2200 250) $PN 1
J 0
(-2195 212);
DISPLAY 0.787234 (-2195 212);
PAINT MONO (-2195 212);
FORCEPROP 1 LASTPIN (-2200 50) $PN 2
J 0
(-2195 60);
DISPLAY 0.787234 (-2195 60);
PAINT MONO (-2195 60);
FORCEPROP 2 LAST CDS_LIB pure_quanta
J 0
(-2200 150);
DISPLAY INVISIBLE (-2200 150);
FORCEPROP 1 LAST PATH I176
J 0
(-2150 325);
DISPLAY 0.978723 (-2150 325);
PAINT WHITE (-2150 325);
DISPLAY INVISIBLE (-2150 325);
FORCEPROP 0 LAST CDS_LOCATION R2511
J 0
(-2150 325);
DISPLAY 1.021277 (-2150 325);
DISPLAY INVISIBLE (-2150 325);
FORCEPROP 0 LAST $SEC 1
J 0
(-2150 325);
DISPLAY 0.680851 (-2150 325);
PAINT MONO (-2150 325);
DISPLAY INVISIBLE (-2150 325);
FORCEPROP 0 LAST CDS_SEC 1
J 0
(-2150 325);
DISPLAY 1.021277 (-2150 325);
DISPLAY INVISIBLE (-2150 325);
FORCEADD OFFPAGE..1
R 2
(4750 1975);
FORCEPROP 2 LAST $XR0 184 
J 0
(4936 1975);
DISPLAY 0.638298 (4936 1975);
PAINT MONO (4936 1975);
FORCEPROP 2 LAST CDS_LIB standard
J 0
(4750 1975);
DISPLAY INVISIBLE (4750 1975);
FORCEPROP 1 LAST OFFPAGE TRUE
J 2
(4425 1850);
DISPLAY 1.170213 (4425 1850);
PAINT GREEN (4425 1850);
DISPLAY INVISIBLE (4425 1850);
FORCEPROP 1 LAST COMMENT_BODY TRUE
J 2
(4625 1875);
DISPLAY 1.170213 (4625 1875);
PAINT GREEN (4625 1875);
DISPLAY INVISIBLE (4625 1875);
FORCEPROP 2 LAST PATH I177
J 0
(4925 2050);
DISPLAY 1.021277 (4925 2050);
DISPLAY INVISIBLE (4925 2050);
FORCEADD OFFPAGE..1
R 2
(4750 2125);
FORCEPROP 2 LAST $XR0 184 
J 0
(4936 2125);
DISPLAY 0.638298 (4936 2125);
PAINT MONO (4936 2125);
FORCEPROP 2 LAST CDS_LIB standard
J 0
(4750 2125);
DISPLAY INVISIBLE (4750 2125);
FORCEPROP 1 LAST OFFPAGE TRUE
J 2
(4425 2000);
DISPLAY 1.170213 (4425 2000);
PAINT GREEN (4425 2000);
DISPLAY INVISIBLE (4425 2000);
FORCEPROP 1 LAST COMMENT_BODY TRUE
J 2
(4625 2025);
DISPLAY 1.170213 (4625 2025);
PAINT GREEN (4625 2025);
DISPLAY INVISIBLE (4625 2025);
FORCEPROP 2 LAST PATH I179
J 0
(4925 2200);
DISPLAY 1.021277 (4925 2200);
DISPLAY INVISIBLE (4925 2200);
FORCEADD OFFPAGE..1
R 2
(4750 2175);
FORCEPROP 2 LAST $XR0 184 
J 0
(4936 2175);
DISPLAY 0.638298 (4936 2175);
PAINT MONO (4936 2175);
FORCEPROP 2 LAST CDS_LIB standard
J 0
(4750 2175);
DISPLAY INVISIBLE (4750 2175);
FORCEPROP 1 LAST OFFPAGE TRUE
J 2
(4425 2050);
DISPLAY 1.170213 (4425 2050);
PAINT GREEN (4425 2050);
DISPLAY INVISIBLE (4425 2050);
FORCEPROP 1 LAST COMMENT_BODY TRUE
J 2
(4625 2075);
DISPLAY 1.170213 (4625 2075);
PAINT GREEN (4625 2075);
DISPLAY INVISIBLE (4625 2075);
FORCEPROP 2 LAST PATH I180
J 0
(4925 2250);
DISPLAY 1.021277 (4925 2250);
DISPLAY INVISIBLE (4925 2250);
FORCEADD OFFPAGE..1
R 2
(4750 2225);
FORCEPROP 2 LAST $XR0 184 
J 0
(4936 2225);
DISPLAY 0.638298 (4936 2225);
PAINT MONO (4936 2225);
FORCEPROP 2 LAST CDS_LIB standard
J 0
(4750 2225);
DISPLAY INVISIBLE (4750 2225);
FORCEPROP 1 LAST OFFPAGE TRUE
J 2
(4425 2100);
DISPLAY 1.170213 (4425 2100);
PAINT GREEN (4425 2100);
DISPLAY INVISIBLE (4425 2100);
FORCEPROP 1 LAST COMMENT_BODY TRUE
J 2
(4625 2125);
DISPLAY 1.170213 (4625 2125);
PAINT GREEN (4625 2125);
DISPLAY INVISIBLE (4625 2125);
FORCEPROP 2 LAST PATH I181
J 0
(4925 2300);
DISPLAY 1.021277 (4925 2300);
DISPLAY INVISIBLE (4925 2300);
FORCEADD Q_RES..1
(1925 525);
FORCEPROP 1 LAST PART_NUMBER CS31002FB08
J 0
(1775 600);
DISPLAY 0.638298 (1775 600);
DISPLAY INVISIBLE (1775 600);
FORCEPROP 1 LAST TOLERANCE 1%
J 0
(2150 525);
DISPLAY 0.638298 (2150 525);
FORCEPROP 1 LAST MATERIAL CHIP
J 0
(2250 525);
DISPLAY 0.638298 (2250 525);
FORCEPROP 1 LAST VALUE 10K
J 2
(2125 525);
DISPLAY 0.638298 (2125 525);
FORCEPROP 1 LAST $LOCATION R4105
J 0
(1700 525);
DISPLAY 0.787234 (1700 525);
FORCEPROP 1 LASTPIN (1825 525) $PN 1
J 0
(1837 537);
DISPLAY 0.787234 (1837 537);
PAINT MONO (1837 537);
FORCEPROP 1 LASTPIN (2025 525) $PN 2
J 0
(1987 537);
DISPLAY 0.787234 (1987 537);
PAINT MONO (1987 537);
FORCEPROP 2 LAST CDS_LIB pure_quanta
J 0
(1925 525);
DISPLAY INVISIBLE (1925 525);
FORCEPROP 1 LAST WATTAGE 1/16W
J 2
(2175 650);
DISPLAY 0.638298 (2175 650);
DISPLAY INVISIBLE (2175 650);
FORCEPROP 1 LAST PACK_TYPE 0402LF
J 0
(1775 650);
DISPLAY 0.638298 (1775 650);
DISPLAY INVISIBLE (1775 650);
FORCEPROP 1 LAST PATH I183
J 0
(1875 675);
DISPLAY 0.978723 (1875 675);
PAINT WHITE (1875 675);
DISPLAY INVISIBLE (1875 675);
FORCEPROP 0 LAST CDS_LOCATION R4105
J 0
(2250 575);
DISPLAY 1.021277 (2250 575);
DISPLAY INVISIBLE (2250 575);
FORCEPROP 0 LAST $SEC 1
J 0
(2250 575);
DISPLAY 0.680851 (2250 575);
PAINT MONO (2250 575);
DISPLAY INVISIBLE (2250 575);
FORCEPROP 0 LAST CDS_SEC 1
J 0
(2250 575);
DISPLAY 1.021277 (2250 575);
DISPLAY INVISIBLE (2250 575);
FORCEADD Q_RES..1
(1925 425);
FORCEPROP 1 LAST PART_NUMBER CS31002FB08
J 0
(1775 500);
DISPLAY 0.638298 (1775 500);
DISPLAY INVISIBLE (1775 500);
FORCEPROP 1 LAST MATERIAL CHIP
J 0
(2250 425);
DISPLAY 0.638298 (2250 425);
FORCEPROP 1 LAST TOLERANCE 1%
J 0
(2150 425);
DISPLAY 0.638298 (2150 425);
FORCEPROP 1 LAST VALUE 10K
J 2
(2125 425);
DISPLAY 0.638298 (2125 425);
FORCEPROP 1 LAST $LOCATION R4106
J 0
(1700 425);
DISPLAY 0.787234 (1700 425);
FORCEPROP 1 LASTPIN (1825 425) $PN 1
J 0
(1837 437);
DISPLAY 0.787234 (1837 437);
PAINT MONO (1837 437);
FORCEPROP 1 LASTPIN (2025 425) $PN 2
J 0
(1987 437);
DISPLAY 0.787234 (1987 437);
PAINT MONO (1987 437);
FORCEPROP 2 LAST CDS_LIB pure_quanta
J 0
(1925 425);
DISPLAY INVISIBLE (1925 425);
FORCEPROP 1 LAST WATTAGE 1/16W
J 2
(2175 550);
DISPLAY 0.638298 (2175 550);
DISPLAY INVISIBLE (2175 550);
FORCEPROP 1 LAST PACK_TYPE 0402LF
J 0
(1775 550);
DISPLAY 0.638298 (1775 550);
DISPLAY INVISIBLE (1775 550);
FORCEPROP 1 LAST PATH I184
J 0
(1875 575);
DISPLAY 0.978723 (1875 575);
PAINT WHITE (1875 575);
DISPLAY INVISIBLE (1875 575);
FORCEPROP 0 LAST CDS_LOCATION R4106
J 0
(2250 475);
DISPLAY 1.021277 (2250 475);
DISPLAY INVISIBLE (2250 475);
FORCEPROP 0 LAST $SEC 1
J 0
(2250 475);
DISPLAY 0.680851 (2250 475);
PAINT MONO (2250 475);
DISPLAY INVISIBLE (2250 475);
FORCEPROP 0 LAST CDS_SEC 1
J 0
(2250 475);
DISPLAY 1.021277 (2250 475);
DISPLAY INVISIBLE (2250 475);
FORCEADD Q_RES..1
(1925 625);
FORCEPROP 1 LAST PART_NUMBER CS31002FB08
J 0
(1775 700);
DISPLAY 0.638298 (1775 700);
DISPLAY INVISIBLE (1775 700);
FORCEPROP 1 LAST MATERIAL CHIP
J 0
(2250 625);
DISPLAY 0.638298 (2250 625);
FORCEPROP 1 LAST TOLERANCE 1%
J 0
(2150 625);
DISPLAY 0.638298 (2150 625);
FORCEPROP 1 LAST VALUE 10K
J 2
(2125 625);
DISPLAY 0.638298 (2125 625);
FORCEPROP 1 LAST $LOCATION R4104
J 0
(1700 625);
DISPLAY 0.787234 (1700 625);
FORCEPROP 1 LASTPIN (1825 625) $PN 1
J 0
(1837 637);
DISPLAY 0.787234 (1837 637);
PAINT MONO (1837 637);
FORCEPROP 1 LASTPIN (2025 625) $PN 2
J 0
(1987 637);
DISPLAY 0.787234 (1987 637);
PAINT MONO (1987 637);
FORCEPROP 1 LAST PACK_TYPE 0402LF
J 0
(1775 750);
DISPLAY 0.638298 (1775 750);
DISPLAY INVISIBLE (1775 750);
FORCEPROP 1 LAST WATTAGE 1/16W
J 2
(2175 750);
DISPLAY 0.638298 (2175 750);
DISPLAY INVISIBLE (2175 750);
FORCEPROP 2 LAST CDS_LIB pure_quanta
J 0
(1925 625);
DISPLAY INVISIBLE (1925 625);
FORCEPROP 1 LAST PATH I185
J 0
(1875 775);
DISPLAY 0.978723 (1875 775);
PAINT WHITE (1875 775);
DISPLAY INVISIBLE (1875 775);
FORCEPROP 0 LAST CDS_LOCATION R4104
J 0
(2250 675);
DISPLAY 1.021277 (2250 675);
DISPLAY INVISIBLE (2250 675);
FORCEPROP 0 LAST $SEC 1
J 0
(2250 675);
DISPLAY 0.680851 (2250 675);
PAINT MONO (2250 675);
DISPLAY INVISIBLE (2250 675);
FORCEPROP 0 LAST CDS_SEC 1
J 0
(2250 675);
DISPLAY 1.021277 (2250 675);
DISPLAY INVISIBLE (2250 675);
FORCEADD Q_RES..1
(1925 725);
FORCEPROP 1 LAST PART_NUMBER CS31002FB08
J 0
(1775 800);
DISPLAY 0.638298 (1775 800);
DISPLAY INVISIBLE (1775 800);
FORCEPROP 1 LAST MATERIAL CHIP
J 0
(2250 725);
DISPLAY 0.638298 (2250 725);
FORCEPROP 1 LAST VALUE 10K
J 2
(2125 725);
DISPLAY 0.638298 (2125 725);
FORCEPROP 1 LAST TOLERANCE 1%
J 0
(2150 725);
DISPLAY 0.638298 (2150 725);
FORCEPROP 1 LAST $LOCATION R4103
J 0
(1700 725);
DISPLAY 0.787234 (1700 725);
FORCEPROP 1 LASTPIN (1825 725) $PN 1
J 0
(1837 737);
DISPLAY 0.787234 (1837 737);
PAINT MONO (1837 737);
FORCEPROP 1 LASTPIN (2025 725) $PN 2
J 0
(1987 737);
DISPLAY 0.787234 (1987 737);
PAINT MONO (1987 737);
FORCEPROP 2 LAST CDS_LIB pure_quanta
J 0
(1925 725);
DISPLAY INVISIBLE (1925 725);
FORCEPROP 1 LAST PATH I186
J 0
(1875 875);
DISPLAY 0.978723 (1875 875);
PAINT WHITE (1875 875);
DISPLAY INVISIBLE (1875 875);
FORCEPROP 1 LAST WATTAGE 1/16W
J 2
(2175 850);
DISPLAY 0.638298 (2175 850);
DISPLAY INVISIBLE (2175 850);
FORCEPROP 1 LAST PACK_TYPE 0402LF
J 0
(1775 850);
DISPLAY 0.638298 (1775 850);
DISPLAY INVISIBLE (1775 850);
FORCEPROP 0 LAST CDS_LOCATION R4103
J 0
(2250 775);
DISPLAY 1.021277 (2250 775);
DISPLAY INVISIBLE (2250 775);
FORCEPROP 0 LAST $SEC 1
J 0
(2250 775);
DISPLAY 0.680851 (2250 775);
PAINT MONO (2250 775);
DISPLAY INVISIBLE (2250 775);
FORCEPROP 0 LAST CDS_SEC 1
J 0
(2250 775);
DISPLAY 1.021277 (2250 775);
DISPLAY INVISIBLE (2250 775);
FORCEADD OFFPAGE..2
R 2
(650 625);
FORCEPROP 2 LAST $XR0 184 
J 0
(395 625);
DISPLAY 0.638298 (395 625);
PAINT MONO (395 625);
FORCEPROP 2 LAST CDS_LIB standard
J 2
(650 625);
DISPLAY INVISIBLE (650 625);
FORCEPROP 1 LAST OFFPAGE TRUE
J 2
(325 500);
DISPLAY 0.872340 (325 500);
DISPLAY INVISIBLE (325 500);
FORCEPROP 1 LAST COMMENT_BODY TRUE
J 2
(695 530);
DISPLAY 0.872340 (695 530);
PAINT GREEN (695 530);
DISPLAY INVISIBLE (695 530);
FORCEPROP 2 LAST PATH I188
J 2
(475 700);
DISPLAY 1.021277 (475 700);
DISPLAY INVISIBLE (475 700);
FORCEADD OFFPAGE..2
R 2
(650 725);
FORCEPROP 2 LAST $XR0 184 
J 0
(395 725);
DISPLAY 0.638298 (395 725);
PAINT MONO (395 725);
FORCEPROP 2 LAST CDS_LIB standard
J 0
(650 725);
DISPLAY INVISIBLE (650 725);
FORCEPROP 1 LAST OFFPAGE TRUE
J 2
(325 600);
DISPLAY 0.872340 (325 600);
DISPLAY INVISIBLE (325 600);
FORCEPROP 1 LAST COMMENT_BODY TRUE
J 2
(695 630);
DISPLAY 0.872340 (695 630);
PAINT GREEN (695 630);
DISPLAY INVISIBLE (695 630);
FORCEPROP 2 LAST PATH I189
J 0
(700 800);
DISPLAY 1.021277 (700 800);
DISPLAY INVISIBLE (700 800);
FORCEADD OFFPAGE..2
R 2
(650 525);
FORCEPROP 2 LAST $XR0 184 
J 0
(395 525);
DISPLAY 0.638298 (395 525);
PAINT MONO (395 525);
FORCEPROP 2 LAST CDS_LIB standard
J 0
(650 525);
DISPLAY INVISIBLE (650 525);
FORCEPROP 1 LAST OFFPAGE TRUE
J 2
(325 400);
DISPLAY 0.872340 (325 400);
DISPLAY INVISIBLE (325 400);
FORCEPROP 1 LAST COMMENT_BODY TRUE
J 2
(695 430);
DISPLAY 0.872340 (695 430);
PAINT GREEN (695 430);
DISPLAY INVISIBLE (695 430);
FORCEPROP 2 LAST PATH I190
J 0
(700 600);
DISPLAY 1.021277 (700 600);
DISPLAY INVISIBLE (700 600);
FORCEADD OFFPAGE..2
R 2
(650 425);
FORCEPROP 2 LAST $XR0 184 
J 0
(395 425);
DISPLAY 0.638298 (395 425);
PAINT MONO (395 425);
FORCEPROP 2 LAST CDS_LIB standard
J 0
(650 425);
DISPLAY INVISIBLE (650 425);
FORCEPROP 1 LAST OFFPAGE TRUE
J 2
(325 300);
DISPLAY 0.872340 (325 300);
DISPLAY INVISIBLE (325 300);
FORCEPROP 1 LAST COMMENT_BODY TRUE
J 2
(695 330);
DISPLAY 0.872340 (695 330);
PAINT GREEN (695 330);
DISPLAY INVISIBLE (695 330);
FORCEPROP 2 LAST PATH I191
J 0
(700 500);
DISPLAY 1.021277 (700 500);
DISPLAY INVISIBLE (700 500);
FORCEADD Q_RES..1
(1925 125);
FORCEPROP 1 LAST PART_NUMBER CS31002FB08
J 0
(1775 200);
DISPLAY 0.638298 (1775 200);
DISPLAY INVISIBLE (1775 200);
FORCEPROP 1 LAST TOLERANCE 1%
J 0
(2150 125);
DISPLAY 0.638298 (2150 125);
FORCEPROP 1 LAST VALUE 10K
J 2
(2125 125);
DISPLAY 0.638298 (2125 125);
FORCEPROP 1 LAST MATERIAL CHIP
J 0
(2250 125);
DISPLAY 0.638298 (2250 125);
FORCEPROP 1 LAST $LOCATION R4109
J 0
(1700 125);
DISPLAY 0.808511 (1700 125);
FORCEPROP 1 LASTPIN (1825 125) $PN 1
J 0
(1837 137);
DISPLAY 0.787234 (1837 137);
PAINT MONO (1837 137);
FORCEPROP 1 LASTPIN (2025 125) $PN 2
J 0
(1987 137);
DISPLAY 0.787234 (1987 137);
PAINT MONO (1987 137);
FORCEPROP 1 LAST PACK_TYPE 0402LF
J 0
(1775 250);
DISPLAY 0.638298 (1775 250);
DISPLAY INVISIBLE (1775 250);
FORCEPROP 1 LAST WATTAGE 1/16W
J 2
(2175 250);
DISPLAY 0.638298 (2175 250);
DISPLAY INVISIBLE (2175 250);
FORCEPROP 2 LAST CDS_LIB pure_quanta
J 0
(1925 125);
DISPLAY INVISIBLE (1925 125);
FORCEPROP 1 LAST PATH I195
J 0
(1875 275);
DISPLAY 0.978723 (1875 275);
PAINT WHITE (1875 275);
DISPLAY INVISIBLE (1875 275);
FORCEPROP 0 LAST CDS_LOCATION R4109
J 0
(2250 175);
DISPLAY 1.021277 (2250 175);
DISPLAY INVISIBLE (2250 175);
FORCEPROP 0 LAST $SEC 1
J 0
(2250 175);
DISPLAY 0.680851 (2250 175);
PAINT MONO (2250 175);
DISPLAY INVISIBLE (2250 175);
FORCEPROP 0 LAST CDS_SEC 1
J 0
(2250 175);
DISPLAY 1.021277 (2250 175);
DISPLAY INVISIBLE (2250 175);
FORCEADD Q_RES..1
(1925 225);
FORCEPROP 1 LAST PART_NUMBER CS31002FB08
J 0
(1775 300);
DISPLAY 0.638298 (1775 300);
DISPLAY INVISIBLE (1775 300);
FORCEPROP 1 LAST TOLERANCE 1%
J 0
(2150 225);
DISPLAY 0.638298 (2150 225);
FORCEPROP 1 LAST VALUE 10K
J 2
(2125 225);
DISPLAY 0.638298 (2125 225);
FORCEPROP 1 LAST MATERIAL CHIP
J 0
(2250 225);
DISPLAY 0.638298 (2250 225);
FORCEPROP 1 LAST $LOCATION R4108
J 0
(1700 225);
DISPLAY 0.808511 (1700 225);
FORCEPROP 1 LASTPIN (1825 225) $PN 1
J 0
(1837 237);
DISPLAY 0.787234 (1837 237);
PAINT MONO (1837 237);
FORCEPROP 1 LASTPIN (2025 225) $PN 2
J 0
(1987 237);
DISPLAY 0.787234 (1987 237);
PAINT MONO (1987 237);
FORCEPROP 2 LAST CDS_LIB pure_quanta
J 0
(1925 225);
DISPLAY INVISIBLE (1925 225);
FORCEPROP 1 LAST WATTAGE 1/16W
J 2
(2175 350);
DISPLAY 0.638298 (2175 350);
DISPLAY INVISIBLE (2175 350);
FORCEPROP 1 LAST PACK_TYPE 0402LF
J 0
(1775 350);
DISPLAY 0.638298 (1775 350);
DISPLAY INVISIBLE (1775 350);
FORCEPROP 1 LAST PATH I196
J 0
(1875 375);
DISPLAY 0.978723 (1875 375);
PAINT WHITE (1875 375);
DISPLAY INVISIBLE (1875 375);
FORCEPROP 0 LAST CDS_LOCATION R4108
J 0
(2250 275);
DISPLAY 1.021277 (2250 275);
DISPLAY INVISIBLE (2250 275);
FORCEPROP 0 LAST $SEC 1
J 0
(2250 275);
DISPLAY 0.680851 (2250 275);
PAINT MONO (2250 275);
DISPLAY INVISIBLE (2250 275);
FORCEPROP 0 LAST CDS_SEC 1
J 0
(2250 275);
DISPLAY 1.021277 (2250 275);
DISPLAY INVISIBLE (2250 275);
FORCEADD Q_RES..1
(1925 325);
FORCEPROP 1 LAST PART_NUMBER CS31002FB08
J 0
(1775 400);
DISPLAY 0.638298 (1775 400);
DISPLAY INVISIBLE (1775 400);
FORCEPROP 1 LAST VALUE 10K
J 2
(2125 325);
DISPLAY 0.638298 (2125 325);
FORCEPROP 1 LAST MATERIAL CHIP
J 0
(2250 325);
DISPLAY 0.638298 (2250 325);
FORCEPROP 1 LAST TOLERANCE 1%
J 0
(2150 325);
DISPLAY 0.638298 (2150 325);
FORCEPROP 1 LAST $LOCATION R4107
J 0
(1700 325);
DISPLAY 0.808511 (1700 325);
FORCEPROP 1 LASTPIN (1825 325) $PN 1
J 0
(1837 337);
DISPLAY 0.787234 (1837 337);
PAINT MONO (1837 337);
FORCEPROP 1 LASTPIN (2025 325) $PN 2
J 0
(1987 337);
DISPLAY 0.787234 (1987 337);
PAINT MONO (1987 337);
FORCEPROP 2 LAST CDS_LIB pure_quanta
J 0
(1925 325);
DISPLAY INVISIBLE (1925 325);
FORCEPROP 1 LAST WATTAGE 1/16W
J 2
(2175 450);
DISPLAY 0.638298 (2175 450);
DISPLAY INVISIBLE (2175 450);
FORCEPROP 1 LAST PACK_TYPE 0402LF
J 0
(1775 450);
DISPLAY 0.638298 (1775 450);
DISPLAY INVISIBLE (1775 450);
FORCEPROP 1 LAST PATH I197
J 0
(1875 475);
DISPLAY 0.978723 (1875 475);
PAINT WHITE (1875 475);
DISPLAY INVISIBLE (1875 475);
FORCEPROP 0 LAST CDS_LOCATION R4107
J 0
(2250 375);
DISPLAY 1.021277 (2250 375);
DISPLAY INVISIBLE (2250 375);
FORCEPROP 0 LAST $SEC 1
J 0
(2250 375);
DISPLAY 0.680851 (2250 375);
PAINT MONO (2250 375);
DISPLAY INVISIBLE (2250 375);
FORCEPROP 0 LAST CDS_SEC 1
J 0
(2250 375);
DISPLAY 1.021277 (2250 375);
DISPLAY INVISIBLE (2250 375);
FORCEADD OFFPAGE..2
R 2
(650 125);
FORCEPROP 2 LAST $XR0 184 
J 0
(395 125);
DISPLAY 0.638298 (395 125);
PAINT MONO (395 125);
FORCEPROP 2 LAST CDS_LIB standard
J 0
(650 125);
DISPLAY INVISIBLE (650 125);
FORCEPROP 1 LAST OFFPAGE TRUE
J 2
(325 0);
DISPLAY 0.872340 (325 0);
DISPLAY INVISIBLE (325 0);
FORCEPROP 1 LAST COMMENT_BODY TRUE
J 2
(695 30);
DISPLAY 0.872340 (695 30);
PAINT GREEN (695 30);
DISPLAY INVISIBLE (695 30);
FORCEPROP 2 LAST PATH I198
J 0
(700 200);
DISPLAY 1.021277 (700 200);
DISPLAY INVISIBLE (700 200);
FORCEADD OFFPAGE..2
R 2
(650 225);
FORCEPROP 2 LAST $XR0 184 
J 0
(395 225);
DISPLAY 0.638298 (395 225);
PAINT MONO (395 225);
FORCEPROP 2 LAST CDS_LIB standard
J 0
(650 225);
DISPLAY INVISIBLE (650 225);
FORCEPROP 1 LAST OFFPAGE TRUE
J 2
(325 100);
DISPLAY 0.872340 (325 100);
DISPLAY INVISIBLE (325 100);
FORCEPROP 1 LAST COMMENT_BODY TRUE
J 2
(695 130);
DISPLAY 0.872340 (695 130);
PAINT GREEN (695 130);
DISPLAY INVISIBLE (695 130);
FORCEPROP 2 LAST PATH I199
J 0
(700 300);
DISPLAY 1.021277 (700 300);
DISPLAY INVISIBLE (700 300);
FORCEADD OFFPAGE..1
(-1950 1775);
FORCEPROP 2 LAST $XR0 199 
J 0
(-2202 1775);
DISPLAY 0.638298 (-2202 1775);
PAINT MONO (-2202 1775);
FORCEPROP 2 LAST CDS_LIB standard
J 0
(-1950 1775);
PAINT MONO (-1950 1775);
DISPLAY INVISIBLE (-1950 1775);
FORCEPROP 1 LAST OFFPAGE TRUE
J 0
(-1625 1650);
DISPLAY 0.872340 (-1625 1650);
DISPLAY INVISIBLE (-1625 1650);
FORCEPROP 1 LAST COMMENT_BODY TRUE
J 0
(-1825 1675);
DISPLAY 1.170213 (-1825 1675);
PAINT GREEN (-1825 1675);
DISPLAY INVISIBLE (-1825 1675);
FORCEPROP 2 LAST PATH I2
J 0
(-1900 1850);
DISPLAY 1.021277 (-1900 1850);
DISPLAY INVISIBLE (-1900 1850);
FORCEADD OFFPAGE..2
(4750 2325);
FORCEPROP 2 LAST $XR0 14 
J 0
(4939 2325);
DISPLAY 0.638298 (4939 2325);
PAINT MONO (4939 2325);
FORCEPROP 2 LAST CDS_LIB standard
J 0
(4750 2325);
DISPLAY INVISIBLE (4750 2325);
FORCEPROP 2 LAST PATH I20
J 0
(4925 2400);
DISPLAY 1.021277 (4925 2400);
DISPLAY INVISIBLE (4925 2400);
FORCEPROP 1 LAST COMMENT_BODY TRUE
J 0
(4705 2230);
DISPLAY 1.170213 (4705 2230);
PAINT GREEN (4705 2230);
DISPLAY INVISIBLE (4705 2230);
FORCEPROP 1 LAST OFFPAGE TRUE
J 0
(5075 2200);
DISPLAY 1.170213 (5075 2200);
PAINT GREEN (5075 2200);
DISPLAY INVISIBLE (5075 2200);
FORCEADD OFFPAGE..2
R 2
(650 325);
FORCEPROP 2 LAST $XR0 184 
J 0
(395 325);
DISPLAY 0.638298 (395 325);
PAINT MONO (395 325);
FORCEPROP 2 LAST CDS_LIB standard
J 0
(650 325);
DISPLAY INVISIBLE (650 325);
FORCEPROP 1 LAST OFFPAGE TRUE
J 2
(325 200);
DISPLAY 0.872340 (325 200);
DISPLAY INVISIBLE (325 200);
FORCEPROP 1 LAST COMMENT_BODY TRUE
J 2
(695 230);
DISPLAY 0.872340 (695 230);
PAINT GREEN (695 230);
DISPLAY INVISIBLE (695 230);
FORCEPROP 2 LAST PATH I200
J 0
(700 400);
DISPLAY 1.021277 (700 400);
DISPLAY INVISIBLE (700 400);
FORCEADD Q_RES..1
(1925 -475);
FORCEPROP 1 LAST PART_NUMBER CS31002FB08
J 0
(1775 -400);
DISPLAY 0.638298 (1775 -400);
DISPLAY INVISIBLE (1775 -400);
FORCEPROP 1 LAST TOLERANCE 1%
J 0
(2150 -475);
DISPLAY 0.638298 (2150 -475);
FORCEPROP 1 LAST VALUE 10K
J 2
(2125 -475);
DISPLAY 0.638298 (2125 -475);
FORCEPROP 1 LAST MATERIAL CHIP
J 0
(2250 -475);
DISPLAY 0.638298 (2250 -475);
FORCEPROP 1 LAST $LOCATION R4115
J 0
(1700 -475);
DISPLAY 0.787234 (1700 -475);
FORCEPROP 1 LASTPIN (1825 -475) $PN 1
J 0
(1837 -463);
DISPLAY 0.787234 (1837 -463);
PAINT MONO (1837 -463);
FORCEPROP 1 LASTPIN (2025 -475) $PN 2
J 0
(1987 -463);
DISPLAY 0.787234 (1987 -463);
PAINT MONO (1987 -463);
FORCEPROP 1 LAST WATTAGE 1/16W
J 2
(2175 -350);
DISPLAY 0.638298 (2175 -350);
DISPLAY INVISIBLE (2175 -350);
FORCEPROP 1 LAST PACK_TYPE 0402LF
J 0
(1775 -350);
DISPLAY 0.638298 (1775 -350);
DISPLAY INVISIBLE (1775 -350);
FORCEPROP 2 LAST CDS_LIB pure_quanta
J 0
(1925 -475);
DISPLAY INVISIBLE (1925 -475);
FORCEPROP 1 LAST PATH I201
J 0
(1875 -325);
DISPLAY 0.978723 (1875 -325);
PAINT WHITE (1875 -325);
DISPLAY INVISIBLE (1875 -325);
FORCEPROP 0 LAST CDS_LOCATION R4115
J 0
(2250 -425);
DISPLAY 1.021277 (2250 -425);
DISPLAY INVISIBLE (2250 -425);
FORCEPROP 0 LAST $SEC 1
J 0
(2250 -425);
DISPLAY 0.680851 (2250 -425);
PAINT MONO (2250 -425);
DISPLAY INVISIBLE (2250 -425);
FORCEPROP 0 LAST CDS_SEC 1
J 0
(2250 -425);
DISPLAY 1.021277 (2250 -425);
DISPLAY INVISIBLE (2250 -425);
FORCEADD Q_RES..1
(1925 25);
FORCEPROP 1 LAST PART_NUMBER CS31002FB08
J 0
(1775 100);
DISPLAY 0.638298 (1775 100);
DISPLAY INVISIBLE (1775 100);
FORCEPROP 1 LAST MATERIAL CHIP
J 0
(2250 25);
DISPLAY 0.638298 (2250 25);
FORCEPROP 1 LAST TOLERANCE 1%
J 0
(2150 25);
DISPLAY 0.638298 (2150 25);
FORCEPROP 1 LAST VALUE 10K
J 2
(2125 25);
DISPLAY 0.638298 (2125 25);
FORCEPROP 1 LAST $LOCATION R4110
J 0
(1700 25);
DISPLAY 0.787234 (1700 25);
FORCEPROP 1 LASTPIN (1825 25) $PN 1
J 0
(1837 37);
DISPLAY 0.787234 (1837 37);
PAINT MONO (1837 37);
FORCEPROP 1 LASTPIN (2025 25) $PN 2
J 0
(1987 37);
DISPLAY 0.787234 (1987 37);
PAINT MONO (1987 37);
FORCEPROP 1 LAST WATTAGE 1/16W
J 2
(2175 150);
DISPLAY 0.638298 (2175 150);
DISPLAY INVISIBLE (2175 150);
FORCEPROP 1 LAST PACK_TYPE 0402LF
J 0
(1775 150);
DISPLAY 0.638298 (1775 150);
DISPLAY INVISIBLE (1775 150);
FORCEPROP 2 LAST CDS_LIB pure_quanta
J 0
(1925 25);
DISPLAY INVISIBLE (1925 25);
FORCEPROP 1 LAST PATH I202
J 0
(1875 175);
DISPLAY 0.978723 (1875 175);
PAINT WHITE (1875 175);
DISPLAY INVISIBLE (1875 175);
FORCEPROP 0 LAST CDS_LOCATION R4110
J 0
(2250 75);
DISPLAY 1.021277 (2250 75);
DISPLAY INVISIBLE (2250 75);
FORCEPROP 0 LAST $SEC 1
J 0
(2250 75);
DISPLAY 0.680851 (2250 75);
PAINT MONO (2250 75);
DISPLAY INVISIBLE (2250 75);
FORCEPROP 0 LAST CDS_SEC 1
J 0
(2250 75);
DISPLAY 1.021277 (2250 75);
DISPLAY INVISIBLE (2250 75);
FORCEADD Q_RES..1
(1925 -175);
FORCEPROP 1 LAST PART_NUMBER CS31002FB08
J 0
(1775 -100);
DISPLAY 0.638298 (1775 -100);
DISPLAY INVISIBLE (1775 -100);
FORCEPROP 1 LAST VALUE 10K
J 2
(2125 -175);
DISPLAY 0.638298 (2125 -175);
FORCEPROP 1 LAST MATERIAL CHIP
J 0
(2250 -175);
DISPLAY 0.638298 (2250 -175);
FORCEPROP 1 LAST TOLERANCE 1%
J 0
(2150 -175);
DISPLAY 0.638298 (2150 -175);
FORCEPROP 1 LAST $LOCATION R4112
J 0
(1700 -175);
DISPLAY 0.787234 (1700 -175);
FORCEPROP 1 LASTPIN (1825 -175) $PN 1
J 0
(1837 -163);
DISPLAY 0.787234 (1837 -163);
PAINT MONO (1837 -163);
FORCEPROP 1 LASTPIN (2025 -175) $PN 2
J 0
(1987 -163);
DISPLAY 0.787234 (1987 -163);
PAINT MONO (1987 -163);
FORCEPROP 1 LAST WATTAGE 1/16W
J 2
(2175 -50);
DISPLAY 0.638298 (2175 -50);
DISPLAY INVISIBLE (2175 -50);
FORCEPROP 1 LAST PACK_TYPE 0402LF
J 0
(1775 -50);
DISPLAY 0.638298 (1775 -50);
DISPLAY INVISIBLE (1775 -50);
FORCEPROP 2 LAST CDS_LIB pure_quanta
J 0
(1925 -175);
DISPLAY INVISIBLE (1925 -175);
FORCEPROP 1 LAST PATH I203
J 0
(1875 -25);
DISPLAY 0.978723 (1875 -25);
PAINT WHITE (1875 -25);
DISPLAY INVISIBLE (1875 -25);
FORCEPROP 0 LAST CDS_LOCATION R4112
J 0
(2250 -125);
DISPLAY 1.021277 (2250 -125);
DISPLAY INVISIBLE (2250 -125);
FORCEPROP 0 LAST $SEC 1
J 0
(2250 -125);
DISPLAY 0.680851 (2250 -125);
PAINT MONO (2250 -125);
DISPLAY INVISIBLE (2250 -125);
FORCEPROP 0 LAST CDS_SEC 1
J 0
(2250 -125);
DISPLAY 1.021277 (2250 -125);
DISPLAY INVISIBLE (2250 -125);
FORCEADD Q_RES..1
(1925 -75);
FORCEPROP 1 LAST PART_NUMBER CS31002FB08
J 0
(1775 0);
DISPLAY 0.638298 (1775 0);
DISPLAY INVISIBLE (1775 0);
FORCEPROP 1 LAST VALUE 10K
J 2
(2125 -75);
DISPLAY 0.638298 (2125 -75);
FORCEPROP 1 LAST TOLERANCE 1%
J 0
(2150 -75);
DISPLAY 0.638298 (2150 -75);
FORCEPROP 1 LAST MATERIAL CHIP
J 0
(2250 -75);
DISPLAY 0.638298 (2250 -75);
FORCEPROP 1 LAST $LOCATION R4111
J 0
(1700 -75);
DISPLAY 0.787234 (1700 -75);
FORCEPROP 1 LASTPIN (1825 -75) $PN 1
J 0
(1837 -63);
DISPLAY 0.787234 (1837 -63);
PAINT MONO (1837 -63);
FORCEPROP 1 LASTPIN (2025 -75) $PN 2
J 0
(1987 -63);
DISPLAY 0.787234 (1987 -63);
PAINT MONO (1987 -63);
FORCEPROP 1 LAST WATTAGE 1/16W
J 2
(2175 50);
DISPLAY 0.638298 (2175 50);
DISPLAY INVISIBLE (2175 50);
FORCEPROP 1 LAST PACK_TYPE 0402LF
J 0
(1775 50);
DISPLAY 0.638298 (1775 50);
DISPLAY INVISIBLE (1775 50);
FORCEPROP 2 LAST CDS_LIB pure_quanta
J 0
(1925 -75);
DISPLAY INVISIBLE (1925 -75);
FORCEPROP 1 LAST PATH I204
J 0
(1875 75);
DISPLAY 0.978723 (1875 75);
PAINT WHITE (1875 75);
DISPLAY INVISIBLE (1875 75);
FORCEPROP 0 LAST CDS_LOCATION R4111
J 0
(2250 -25);
DISPLAY 1.021277 (2250 -25);
DISPLAY INVISIBLE (2250 -25);
FORCEPROP 0 LAST $SEC 1
J 0
(2250 -25);
DISPLAY 0.680851 (2250 -25);
PAINT MONO (2250 -25);
DISPLAY INVISIBLE (2250 -25);
FORCEPROP 0 LAST CDS_SEC 1
J 0
(2250 -25);
DISPLAY 1.021277 (2250 -25);
DISPLAY INVISIBLE (2250 -25);
FORCEADD Q_RES..1
(1925 -375);
FORCEPROP 1 LAST PART_NUMBER CS31002FB08
J 0
(1775 -300);
DISPLAY 0.638298 (1775 -300);
DISPLAY INVISIBLE (1775 -300);
FORCEPROP 1 LAST TOLERANCE 1%
J 0
(2150 -375);
DISPLAY 0.638298 (2150 -375);
FORCEPROP 1 LAST VALUE 10K
J 2
(2125 -375);
DISPLAY 0.638298 (2125 -375);
FORCEPROP 1 LAST MATERIAL CHIP
J 0
(2250 -375);
DISPLAY 0.638298 (2250 -375);
FORCEPROP 1 LAST $LOCATION R4114
J 0
(1700 -375);
DISPLAY 0.787234 (1700 -375);
FORCEPROP 1 LASTPIN (1825 -375) $PN 1
J 0
(1837 -363);
DISPLAY 0.787234 (1837 -363);
PAINT MONO (1837 -363);
FORCEPROP 1 LASTPIN (2025 -375) $PN 2
J 0
(1987 -363);
DISPLAY 0.787234 (1987 -363);
PAINT MONO (1987 -363);
FORCEPROP 1 LAST WATTAGE 1/16W
J 2
(2175 -250);
DISPLAY 0.638298 (2175 -250);
DISPLAY INVISIBLE (2175 -250);
FORCEPROP 1 LAST PACK_TYPE 0402LF
J 0
(1775 -250);
DISPLAY 0.638298 (1775 -250);
DISPLAY INVISIBLE (1775 -250);
FORCEPROP 2 LAST CDS_LIB pure_quanta
J 0
(1925 -375);
DISPLAY INVISIBLE (1925 -375);
FORCEPROP 1 LAST PATH I205
J 0
(1875 -225);
DISPLAY 0.978723 (1875 -225);
PAINT WHITE (1875 -225);
DISPLAY INVISIBLE (1875 -225);
FORCEPROP 0 LAST CDS_LOCATION R4114
J 0
(2250 -325);
DISPLAY 1.021277 (2250 -325);
DISPLAY INVISIBLE (2250 -325);
FORCEPROP 0 LAST $SEC 1
J 0
(2250 -325);
DISPLAY 0.680851 (2250 -325);
PAINT MONO (2250 -325);
DISPLAY INVISIBLE (2250 -325);
FORCEPROP 0 LAST CDS_SEC 1
J 0
(2250 -325);
DISPLAY 1.021277 (2250 -325);
DISPLAY INVISIBLE (2250 -325);
FORCEADD Q_RES..1
(1925 -275);
FORCEPROP 1 LAST PART_NUMBER CS31002FB08
J 0
(1775 -200);
DISPLAY 0.638298 (1775 -200);
DISPLAY INVISIBLE (1775 -200);
FORCEPROP 1 LAST TOLERANCE 1%
J 0
(2150 -275);
DISPLAY 0.638298 (2150 -275);
FORCEPROP 1 LAST VALUE 10K
J 2
(2125 -275);
DISPLAY 0.638298 (2125 -275);
FORCEPROP 1 LAST MATERIAL CHIP
J 0
(2250 -275);
DISPLAY 0.638298 (2250 -275);
FORCEPROP 1 LAST $LOCATION R4113
J 0
(1700 -275);
DISPLAY 0.787234 (1700 -275);
FORCEPROP 1 LASTPIN (1825 -275) $PN 1
J 0
(1837 -263);
DISPLAY 0.787234 (1837 -263);
PAINT MONO (1837 -263);
FORCEPROP 1 LASTPIN (2025 -275) $PN 2
J 0
(1987 -263);
DISPLAY 0.787234 (1987 -263);
PAINT MONO (1987 -263);
FORCEPROP 1 LAST WATTAGE 1/16W
J 2
(2175 -150);
DISPLAY 0.638298 (2175 -150);
DISPLAY INVISIBLE (2175 -150);
FORCEPROP 1 LAST PACK_TYPE 0402LF
J 0
(1775 -150);
DISPLAY 0.638298 (1775 -150);
DISPLAY INVISIBLE (1775 -150);
FORCEPROP 2 LAST CDS_LIB pure_quanta
J 0
(1925 -275);
DISPLAY INVISIBLE (1925 -275);
FORCEPROP 1 LAST PATH I206
J 0
(1875 -125);
DISPLAY 0.978723 (1875 -125);
PAINT WHITE (1875 -125);
DISPLAY INVISIBLE (1875 -125);
FORCEPROP 0 LAST CDS_LOCATION R4113
J 0
(2250 -225);
DISPLAY 1.021277 (2250 -225);
DISPLAY INVISIBLE (2250 -225);
FORCEPROP 0 LAST $SEC 1
J 0
(2250 -225);
DISPLAY 0.680851 (2250 -225);
PAINT MONO (2250 -225);
DISPLAY INVISIBLE (2250 -225);
FORCEPROP 0 LAST CDS_SEC 1
J 0
(2250 -225);
DISPLAY 1.021277 (2250 -225);
DISPLAY INVISIBLE (2250 -225);
FORCEADD Q_RES..1
(1925 -575);
FORCEPROP 1 LAST PART_NUMBER CS31002FB08
J 0
(1775 -500);
DISPLAY 0.638298 (1775 -500);
DISPLAY INVISIBLE (1775 -500);
FORCEPROP 1 LAST VALUE 10K
J 2
(2125 -575);
DISPLAY 0.638298 (2125 -575);
FORCEPROP 1 LAST TOLERANCE 1%
J 0
(2150 -575);
DISPLAY 0.638298 (2150 -575);
FORCEPROP 1 LAST MATERIAL CHIP
J 0
(2250 -575);
DISPLAY 0.638298 (2250 -575);
FORCEPROP 1 LAST $LOCATION R4116
J 0
(1700 -575);
DISPLAY 0.787234 (1700 -575);
FORCEPROP 1 LASTPIN (1825 -575) $PN 1
J 0
(1837 -563);
DISPLAY 0.787234 (1837 -563);
PAINT MONO (1837 -563);
FORCEPROP 1 LASTPIN (2025 -575) $PN 2
J 0
(1987 -563);
DISPLAY 0.787234 (1987 -563);
PAINT MONO (1987 -563);
FORCEPROP 2 LAST CDS_LIB pure_quanta
J 0
(1925 -575);
DISPLAY INVISIBLE (1925 -575);
FORCEPROP 1 LAST PACK_TYPE 0402LF
J 0
(1775 -450);
DISPLAY 0.638298 (1775 -450);
DISPLAY INVISIBLE (1775 -450);
FORCEPROP 1 LAST WATTAGE 1/16W
J 2
(2175 -450);
DISPLAY 0.638298 (2175 -450);
DISPLAY INVISIBLE (2175 -450);
FORCEPROP 1 LAST PATH I207
J 0
(1875 -425);
DISPLAY 0.978723 (1875 -425);
PAINT WHITE (1875 -425);
DISPLAY INVISIBLE (1875 -425);
FORCEPROP 0 LAST CDS_LOCATION R4116
J 0
(2250 -525);
DISPLAY 1.021277 (2250 -525);
DISPLAY INVISIBLE (2250 -525);
FORCEPROP 0 LAST $SEC 1
J 0
(2250 -525);
DISPLAY 0.680851 (2250 -525);
PAINT MONO (2250 -525);
DISPLAY INVISIBLE (2250 -525);
FORCEPROP 0 LAST CDS_SEC 1
J 0
(2250 -525);
DISPLAY 1.021277 (2250 -525);
DISPLAY INVISIBLE (2250 -525);
FORCEADD UNIVERSAL_GND..1
(2450 -1075);
FORCEPROP 3 LASTPIN (2450 -1025) SIG_NAME GND\g
J 0
(2460 -1015);
DISPLAY 0.659574 (2460 -1015);
PAINT MONO (2460 -1015);
DISPLAY INVISIBLE (2460 -1015);
FORCEPROP 2 LAST CDS_LIB logical_power
J 0
(2450 -1075);
DISPLAY INVISIBLE (2450 -1075);
FORCEPROP 1 LAST HDL_POWER GND
J 1
(2475 -1150);
DISPLAY 0.872340 (2475 -1150);
PAINT GREEN (2475 -1150);
DISPLAY INVISIBLE (2475 -1150);
FORCEPROP 1 LAST PATH I208
J 0
(2525 -1075);
DISPLAY 0.872340 (2525 -1075);
PAINT AQUA (2525 -1075);
DISPLAY INVISIBLE (2525 -1075);
FORCEADD Q_RES..1
(1925 -675);
FORCEPROP 1 LAST PART_NUMBER CS31002FB08
J 0
(1775 -600);
DISPLAY 0.638298 (1775 -600);
DISPLAY INVISIBLE (1775 -600);
FORCEPROP 1 LAST VALUE 10K
J 2
(2125 -675);
DISPLAY 0.638298 (2125 -675);
FORCEPROP 1 LAST TOLERANCE 1%
J 0
(2150 -675);
DISPLAY 0.638298 (2150 -675);
FORCEPROP 1 LAST MATERIAL CHIP
J 0
(2250 -675);
DISPLAY 0.638298 (2250 -675);
FORCEPROP 1 LAST $LOCATION R4117
J 0
(1700 -675);
DISPLAY 0.787234 (1700 -675);
FORCEPROP 1 LASTPIN (1825 -675) $PN 1
J 0
(1837 -663);
DISPLAY 0.787234 (1837 -663);
PAINT MONO (1837 -663);
FORCEPROP 1 LASTPIN (2025 -675) $PN 2
J 0
(1987 -663);
DISPLAY 0.787234 (1987 -663);
PAINT MONO (1987 -663);
FORCEPROP 1 LAST PACK_TYPE 0402LF
J 0
(1775 -550);
DISPLAY 0.638298 (1775 -550);
DISPLAY INVISIBLE (1775 -550);
FORCEPROP 1 LAST WATTAGE 1/16W
J 2
(2175 -550);
DISPLAY 0.638298 (2175 -550);
DISPLAY INVISIBLE (2175 -550);
FORCEPROP 2 LAST CDS_LIB pure_quanta
J 0
(1925 -675);
DISPLAY INVISIBLE (1925 -675);
FORCEPROP 1 LAST PATH I209
J 0
(1875 -525);
DISPLAY 0.978723 (1875 -525);
PAINT WHITE (1875 -525);
DISPLAY INVISIBLE (1875 -525);
FORCEPROP 0 LAST CDS_LOCATION R4117
J 0
(2250 -625);
DISPLAY 1.021277 (2250 -625);
DISPLAY INVISIBLE (2250 -625);
FORCEPROP 0 LAST $SEC 1
J 0
(2250 -625);
DISPLAY 0.680851 (2250 -625);
PAINT MONO (2250 -625);
DISPLAY INVISIBLE (2250 -625);
FORCEPROP 0 LAST CDS_SEC 1
J 0
(2250 -625);
DISPLAY 1.021277 (2250 -625);
DISPLAY INVISIBLE (2250 -625);
FORCEADD OFFPAGE..1
R 2
(4750 2375);
FORCEPROP 2 LAST $XR0 14 
J 0
(4936 2375);
DISPLAY 0.638298 (4936 2375);
PAINT MONO (4936 2375);
FORCEPROP 2 LAST CDS_LIB standard
J 0
(4750 2375);
PAINT MONO (4750 2375);
DISPLAY INVISIBLE (4750 2375);
FORCEPROP 1 LAST OFFPAGE TRUE
J 2
(4425 2250);
DISPLAY 1.170213 (4425 2250);
PAINT GREEN (4425 2250);
DISPLAY INVISIBLE (4425 2250);
FORCEPROP 1 LAST COMMENT_BODY TRUE
J 2
(4625 2275);
DISPLAY 1.170213 (4625 2275);
PAINT GREEN (4625 2275);
DISPLAY INVISIBLE (4625 2275);
FORCEPROP 2 LAST PATH I21
J 0
(4925 2450);
DISPLAY 1.021277 (4925 2450);
DISPLAY INVISIBLE (4925 2450);
FORCEADD OFFPAGE..2
R 2
(650 -475);
FORCEPROP 2 LAST $XR0 184 
J 0
(395 -475);
DISPLAY 0.638298 (395 -475);
PAINT MONO (395 -475);
FORCEPROP 2 LAST CDS_LIB standard
J 0
(650 -475);
DISPLAY INVISIBLE (650 -475);
FORCEPROP 1 LAST OFFPAGE TRUE
J 2
(325 -600);
DISPLAY 0.872340 (325 -600);
DISPLAY INVISIBLE (325 -600);
FORCEPROP 1 LAST COMMENT_BODY TRUE
J 2
(695 -570);
DISPLAY 0.872340 (695 -570);
PAINT GREEN (695 -570);
DISPLAY INVISIBLE (695 -570);
FORCEPROP 2 LAST PATH I210
J 0
(700 -400);
DISPLAY 1.021277 (700 -400);
DISPLAY INVISIBLE (700 -400);
FORCEADD OFFPAGE..2
R 2
(650 -375);
FORCEPROP 2 LAST $XR0 184 
J 0
(395 -375);
DISPLAY 0.638298 (395 -375);
PAINT MONO (395 -375);
FORCEPROP 2 LAST CDS_LIB standard
J 0
(650 -375);
DISPLAY INVISIBLE (650 -375);
FORCEPROP 1 LAST OFFPAGE TRUE
J 2
(325 -500);
DISPLAY 0.872340 (325 -500);
DISPLAY INVISIBLE (325 -500);
FORCEPROP 1 LAST COMMENT_BODY TRUE
J 2
(695 -470);
DISPLAY 0.872340 (695 -470);
PAINT GREEN (695 -470);
DISPLAY INVISIBLE (695 -470);
FORCEPROP 2 LAST PATH I211
J 0
(700 -300);
DISPLAY 1.021277 (700 -300);
DISPLAY INVISIBLE (700 -300);
FORCEADD OFFPAGE..2
R 2
(650 -275);
FORCEPROP 2 LAST $XR0 184 
J 0
(395 -275);
DISPLAY 0.638298 (395 -275);
PAINT MONO (395 -275);
FORCEPROP 2 LAST CDS_LIB standard
J 0
(650 -275);
DISPLAY INVISIBLE (650 -275);
FORCEPROP 1 LAST OFFPAGE TRUE
J 2
(325 -400);
DISPLAY 0.872340 (325 -400);
DISPLAY INVISIBLE (325 -400);
FORCEPROP 1 LAST COMMENT_BODY TRUE
J 2
(695 -370);
DISPLAY 0.872340 (695 -370);
PAINT GREEN (695 -370);
DISPLAY INVISIBLE (695 -370);
FORCEPROP 2 LAST PATH I212
J 0
(700 -200);
DISPLAY 1.021277 (700 -200);
DISPLAY INVISIBLE (700 -200);
FORCEADD OFFPAGE..2
R 2
(650 -175);
FORCEPROP 2 LAST $XR0 184 
J 0
(395 -175);
DISPLAY 0.638298 (395 -175);
PAINT MONO (395 -175);
FORCEPROP 2 LAST CDS_LIB standard
J 0
(650 -175);
DISPLAY INVISIBLE (650 -175);
FORCEPROP 1 LAST OFFPAGE TRUE
J 2
(325 -300);
DISPLAY 0.872340 (325 -300);
DISPLAY INVISIBLE (325 -300);
FORCEPROP 1 LAST COMMENT_BODY TRUE
J 2
(695 -270);
DISPLAY 0.872340 (695 -270);
PAINT GREEN (695 -270);
DISPLAY INVISIBLE (695 -270);
FORCEPROP 2 LAST PATH I213
J 0
(700 -100);
DISPLAY 1.021277 (700 -100);
DISPLAY INVISIBLE (700 -100);
FORCEADD OFFPAGE..2
R 2
(650 -75);
FORCEPROP 2 LAST $XR0 184 
J 0
(395 -75);
DISPLAY 0.638298 (395 -75);
PAINT MONO (395 -75);
FORCEPROP 2 LAST CDS_LIB standard
J 0
(650 -75);
DISPLAY INVISIBLE (650 -75);
FORCEPROP 1 LAST OFFPAGE TRUE
J 2
(325 -200);
DISPLAY 0.872340 (325 -200);
DISPLAY INVISIBLE (325 -200);
FORCEPROP 1 LAST COMMENT_BODY TRUE
J 2
(695 -170);
DISPLAY 0.872340 (695 -170);
PAINT GREEN (695 -170);
DISPLAY INVISIBLE (695 -170);
FORCEPROP 2 LAST PATH I214
J 0
(700 0);
DISPLAY 1.021277 (700 0);
DISPLAY INVISIBLE (700 0);
FORCEADD OFFPAGE..2
R 2
(650 25);
FORCEPROP 2 LAST $XR0 184 
J 0
(395 25);
DISPLAY 0.638298 (395 25);
PAINT MONO (395 25);
FORCEPROP 2 LAST CDS_LIB standard
J 0
(650 25);
DISPLAY INVISIBLE (650 25);
FORCEPROP 1 LAST OFFPAGE TRUE
J 2
(325 -100);
DISPLAY 0.872340 (325 -100);
DISPLAY INVISIBLE (325 -100);
FORCEPROP 1 LAST COMMENT_BODY TRUE
J 2
(695 -70);
DISPLAY 0.872340 (695 -70);
PAINT GREEN (695 -70);
DISPLAY INVISIBLE (695 -70);
FORCEPROP 2 LAST PATH I215
J 0
(700 100);
DISPLAY 1.021277 (700 100);
DISPLAY INVISIBLE (700 100);
FORCEADD OFFPAGE..2
R 2
(650 -675);
FORCEPROP 2 LAST $XR0 184 
J 0
(395 -675);
DISPLAY 0.638298 (395 -675);
PAINT MONO (395 -675);
FORCEPROP 2 LAST CDS_LIB standard
J 0
(650 -675);
DISPLAY INVISIBLE (650 -675);
FORCEPROP 1 LAST OFFPAGE TRUE
J 2
(325 -800);
DISPLAY 0.872340 (325 -800);
DISPLAY INVISIBLE (325 -800);
FORCEPROP 1 LAST COMMENT_BODY TRUE
J 2
(695 -770);
DISPLAY 0.872340 (695 -770);
PAINT GREEN (695 -770);
DISPLAY INVISIBLE (695 -770);
FORCEPROP 2 LAST PATH I216
J 0
(700 -600);
DISPLAY 1.021277 (700 -600);
DISPLAY INVISIBLE (700 -600);
FORCEADD OFFPAGE..2
R 2
(650 -575);
FORCEPROP 2 LAST $XR0 184 
J 0
(395 -575);
DISPLAY 0.638298 (395 -575);
PAINT MONO (395 -575);
FORCEPROP 2 LAST CDS_LIB standard
J 0
(650 -575);
DISPLAY INVISIBLE (650 -575);
FORCEPROP 1 LAST OFFPAGE TRUE
J 2
(325 -700);
DISPLAY 0.872340 (325 -700);
DISPLAY INVISIBLE (325 -700);
FORCEPROP 1 LAST COMMENT_BODY TRUE
J 2
(695 -670);
DISPLAY 0.872340 (695 -670);
PAINT GREEN (695 -670);
DISPLAY INVISIBLE (695 -670);
FORCEPROP 2 LAST PATH I217
J 0
(700 -500);
DISPLAY 1.021277 (700 -500);
DISPLAY INVISIBLE (700 -500);
FORCEADD EMMITSBURG_REV0P9..6
(1600 2400);
FORCEPROP 1 LAST PART_NUMBER AJ0QV2N0T00
J 0
(-228 3520);
DISPLAY 0.723404 (-228 3520);
PAINT GREEN (-228 3520);
DISPLAY INVISIBLE (-228 3520);
FORCEPROP 2 LAST VALUE GFNOCPU04302300-QV2N-MM#99A1WT
J 0
(-225 3725);
DISPLAY 1.021277 (-225 3725);
FORCEPROP 2 LAST PART_TYPE SMLF
J 0
(-225 3775);
DISPLAY 1.021277 (-225 3775);
FORCEPROP 1 LAST MATERIAL IC
J 0
(-228 3393);
DISPLAY 0.723404 (-228 3393);
PAINT GREEN (-228 3393);
FORCEPROP 1 LAST $LOCATION U4
J 0
(-228 3667);
DISPLAY 0.723404 (-228 3667);
PAINT GREEN (-228 3667);
FORCEPROP 2 LASTPIN (-375 2275) $PN BA26
J 2
(-385 2285);
DISPLAY 0.808511 (-385 2285);
FORCEPROP 2 LASTPIN (-375 2325) $PN BA23
J 2
(-385 2335);
DISPLAY 0.808511 (-385 2335);
FORCEPROP 2 LASTPIN (-375 2375) $PN AW23
J 2
(-385 2385);
DISPLAY 0.808511 (-385 2385);
FORCEPROP 2 LASTPIN (-375 2425) $PN BB21
J 2
(-385 2435);
DISPLAY 0.808511 (-385 2435);
FORCEPROP 2 LASTPIN (-375 2475) $PN AV24
J 2
(-385 2485);
DISPLAY 0.808511 (-385 2485);
FORCEPROP 2 LASTPIN (-375 2525) $PN AV28
J 2
(-385 2535);
DISPLAY 0.808511 (-385 2535);
FORCEPROP 2 LASTPIN (-375 2575) $PN BB24
J 2
(-385 2585);
DISPLAY 0.808511 (-385 2585);
FORCEPROP 2 LASTPIN (-375 2625) $PN AW32
J 2
(-385 2635);
DISPLAY 0.808511 (-385 2635);
FORCEPROP 2 LASTPIN (-375 2675) $PN AW36
J 2
(-385 2685);
DISPLAY 0.808511 (-385 2685);
FORCEPROP 2 LASTPIN (-375 2725) $PN BA29
J 2
(-385 2735);
DISPLAY 0.808511 (-385 2735);
FORCEPROP 2 LASTPIN (-375 2775) $PN AV31
J 2
(-385 2785);
DISPLAY 0.808511 (-385 2785);
FORCEPROP 2 LASTPIN (-375 2825) $PN AV34
J 2
(-385 2835);
DISPLAY 0.808511 (-385 2835);
FORCEPROP 2 LASTPIN (-375 2875) $PN BB28
J 2
(-385 2885);
DISPLAY 0.808511 (-385 2885);
FORCEPROP 2 LASTPIN (-375 2925) $PN BA32
J 2
(-385 2935);
DISPLAY 0.808511 (-385 2935);
FORCEPROP 2 LASTPIN (-375 2975) $PN BB34
J 2
(-385 2985);
DISPLAY 0.808511 (-385 2985);
FORCEPROP 2 LASTPIN (-375 3025) $PN AW20
J 2
(-385 3035);
DISPLAY 0.808511 (-385 3035);
FORCEPROP 2 LASTPIN (-375 3075) $PN AW29
J 2
(-385 3085);
DISPLAY 0.808511 (-385 3085);
FORCEPROP 2 LASTPIN (-375 3125) $PN BA36
J 2
(-385 3135);
DISPLAY 0.808511 (-385 3135);
FORCEPROP 2 LASTPIN (-375 3175) $PN BA20
J 2
(-385 3185);
DISPLAY 0.808511 (-385 3185);
FORCEPROP 2 LASTPIN (-375 3225) $PN BB31
J 2
(-385 3235);
DISPLAY 0.808511 (-385 3235);
FORCEPROP 2 LASTPIN (3575 2825) $PN U3
J 0
(3585 2835);
DISPLAY 0.808511 (3585 2835);
FORCEPROP 2 LASTPIN (3575 2875) $PN N2
J 0
(3585 2885);
DISPLAY 0.808511 (3585 2885);
FORCEPROP 2 LASTPIN (3575 2925) $PN P1
J 0
(3585 2935);
DISPLAY 0.808511 (3585 2935);
FORCEPROP 2 LASTPIN (3575 2975) $PN R2
J 0
(3585 2985);
DISPLAY 0.808511 (3585 2985);
FORCEPROP 2 LASTPIN (3575 3025) $PN U1
J 0
(3585 3035);
DISPLAY 0.808511 (3585 3035);
FORCEPROP 2 LASTPIN (3575 3075) $PN V4
J 0
(3585 3085);
DISPLAY 0.808511 (3585 3085);
FORCEPROP 2 LASTPIN (3575 3125) $PN N4
J 0
(3585 3135);
DISPLAY 0.808511 (3585 3135);
FORCEPROP 2 LASTPIN (3575 3175) $PN P3
J 0
(3585 3185);
DISPLAY 0.808511 (3585 3185);
FORCEPROP 2 LASTPIN (3575 3225) $PN R4
J 0
(3585 3235);
DISPLAY 0.808511 (3585 3235);
FORCEPROP 2 LASTPIN (3575 2325) $PN AF8
J 0
(3585 2335);
DISPLAY 0.808511 (3585 2335);
FORCEPROP 2 LASTPIN (3575 2375) $PN AE7
J 0
(3585 2385);
DISPLAY 0.808511 (3585 2385);
FORCEPROP 2 LASTPIN (3575 2425) $PN AC10
J 0
(3585 2435);
DISPLAY 0.808511 (3585 2435);
FORCEPROP 2 LASTPIN (3575 2475) $PN AF11
J 0
(3585 2485);
DISPLAY 0.808511 (3585 2485);
FORCEPROP 2 LASTPIN (3575 2525) $PN AG7
J 0
(3585 2535);
DISPLAY 0.808511 (3585 2535);
FORCEPROP 2 LASTPIN (3575 2575) $PN AB8
J 0
(3585 2585);
DISPLAY 0.808511 (3585 2585);
FORCEPROP 2 LASTPIN (3575 2625) $PN AG10
J 0
(3585 2635);
DISPLAY 0.808511 (3585 2635);
FORCEPROP 2 LASTPIN (3575 2675) $PN AC7
J 0
(3585 2685);
DISPLAY 0.808511 (3585 2685);
FORCEPROP 2 LASTPIN (3575 2725) $PN AE10
J 0
(3585 2735);
DISPLAY 0.808511 (3585 2735);
FORCEPROP 2 LASTPIN (3575 1575) $PN N7
J 0
(3585 1585);
DISPLAY 0.808511 (3585 1585);
FORCEPROP 2 LASTPIN (3575 1625) $PN AA13
J 0
(3585 1635);
DISPLAY 0.808511 (3585 1635);
FORCEPROP 2 LASTPIN (3575 1675) $PN AA7
J 0
(3585 1685);
DISPLAY 0.808511 (3585 1685);
FORCEPROP 2 LASTPIN (3575 1725) $PN AA10
J 0
(3585 1735);
DISPLAY 0.808511 (3585 1735);
FORCEPROP 2 LASTPIN (3575 1775) $PN W7
J 0
(3585 1785);
DISPLAY 0.808511 (3585 1785);
FORCEPROP 2 LASTPIN (3575 1825) $PN V8
J 0
(3585 1835);
DISPLAY 0.808511 (3585 1835);
FORCEPROP 2 LASTPIN (3575 1875) $PN R10
J 0
(3585 1885);
DISPLAY 0.808511 (3585 1885);
FORCEPROP 2 LASTPIN (3575 1925) $PN AB11
J 0
(3585 1935);
DISPLAY 0.808511 (3585 1935);
FORCEPROP 2 LASTPIN (3575 1975) $PN W10
J 0
(3585 1985);
DISPLAY 0.808511 (3585 1985);
FORCEPROP 2 LASTPIN (3575 2025) $PN R7
J 0
(3585 2035);
DISPLAY 0.808511 (3585 2035);
FORCEPROP 2 LASTPIN (3575 2075) $PN U7
J 0
(3585 2085);
DISPLAY 0.808511 (3585 2085);
FORCEPROP 2 LASTPIN (3575 2125) $PN T8
J 0
(3585 2135);
DISPLAY 0.808511 (3585 2135);
FORCEPROP 2 LASTPIN (3575 2175) $PN N10
J 0
(3585 2185);
DISPLAY 0.808511 (3585 2185);
FORCEPROP 2 LASTPIN (3575 2225) $PN W13
J 0
(3585 2235);
DISPLAY 0.808511 (3585 2235);
FORCEPROP 2 LASTPIN (-375 1775) $PN G4
J 2
(-385 1785);
DISPLAY 0.808511 (-385 1785);
FORCEPROP 2 LASTPIN (-375 1825) $PN K1
J 2
(-385 1835);
DISPLAY 0.808511 (-385 1835);
FORCEPROP 2 LASTPIN (-375 1875) $PN L2
J 2
(-385 1885);
DISPLAY 0.808511 (-385 1885);
FORCEPROP 2 LASTPIN (-375 1925) $PN K3
J 2
(-385 1935);
DISPLAY 0.808511 (-385 1935);
FORCEPROP 2 LASTPIN (-375 1975) $PN J2
J 2
(-385 1985);
DISPLAY 0.808511 (-385 1985);
FORCEPROP 2 LASTPIN (-375 2025) $PN G2
J 2
(-385 2035);
DISPLAY 0.808511 (-385 2035);
FORCEPROP 2 LASTPIN (-375 2075) $PN H3
J 2
(-385 2085);
DISPLAY 0.808511 (-385 2085);
FORCEPROP 2 LASTPIN (-375 2125) $PN J4
J 2
(-385 2135);
DISPLAY 0.808511 (-385 2135);
FORCEPROP 2 LASTPIN (-375 2175) $PN L4
J 2
(-385 2185);
DISPLAY 0.808511 (-385 2185);
FORCEPROP 2 LAST CDS_LIB pure_quanta
J 0
(1600 2400);
PAINT MONO (1600 2400);
DISPLAY INVISIBLE (1600 2400);
FORCEPROP 1 LAST CDS_LMAN_SYM_OUTLINE -1825,975,1825,-975
J 0
(1600 2400);
DISPLAY 0.468085 (1600 2400);
PAINT GREEN (1600 2400);
DISPLAY INVISIBLE (1600 2400);
FORCEPROP 1 LAST NEEDS_NO_SIZE TRUE
J 0
(1600 2400);
DISPLAY 0.723404 (1600 2400);
PAINT GREEN (1600 2400);
DISPLAY INVISIBLE (1600 2400);
FORCEPROP 1 LAST PATH I22
J 0
(1600 2400);
DISPLAY 0.723404 (1600 2400);
PAINT GREEN (1600 2400);
DISPLAY INVISIBLE (1600 2400);
FORCEPROP 2 LAST CDS_LOCATION U4
J 0
(-200 3550);
DISPLAY 1.021277 (-200 3550);
DISPLAY INVISIBLE (-200 3550);
FORCEPROP 2 LAST $SEC 6
J 0
(-225 3825);
DISPLAY 0.680851 (-225 3825);
PAINT MONO (-225 3825);
DISPLAY INVISIBLE (-225 3825);
FORCEPROP 2 LAST CDS_SEC 6
J 0
(-200 3550);
DISPLAY 1.021277 (-200 3550);
DISPLAY INVISIBLE (-200 3550);
FORCEADD OFFPAGE..5
(-1950 2425);
FORCEPROP 2 LAST $XR0 184 
J 0
(-2205 2425);
DISPLAY 0.638298 (-2205 2425);
PAINT MONO (-2205 2425);
FORCEPROP 2 LAST CDS_LIB standard
J 0
(-1950 2425);
DISPLAY INVISIBLE (-1950 2425);
FORCEPROP 1 LAST OFFPAGE TRUE
J 0
(-1625 2300);
DISPLAY 0.872340 (-1625 2300);
DISPLAY INVISIBLE (-1625 2300);
FORCEPROP 1 LAST COMMENT_BODY TRUE
J 0
(-1850 2350);
DISPLAY 1.170213 (-1850 2350);
PAINT GREEN (-1850 2350);
DISPLAY INVISIBLE (-1850 2350);
FORCEPROP 2 LAST PATH I225
J 0
(-1900 2500);
DISPLAY 1.021277 (-1900 2500);
DISPLAY INVISIBLE (-1900 2500);
FORCEADD OFFPAGE..1
(-1950 2975);
FORCEPROP 2 LAST $XR0 184 
J 0
(-2202 2975);
DISPLAY 0.638298 (-2202 2975);
PAINT MONO (-2202 2975);
FORCEPROP 2 LAST CDS_LIB standard
J 0
(-1950 2975);
DISPLAY INVISIBLE (-1950 2975);
FORCEPROP 1 LAST OFFPAGE TRUE
J 0
(-1625 2850);
DISPLAY 0.872340 (-1625 2850);
DISPLAY INVISIBLE (-1625 2850);
FORCEPROP 1 LAST COMMENT_BODY TRUE
J 0
(-1825 2875);
DISPLAY 1.170213 (-1825 2875);
PAINT GREEN (-1825 2875);
DISPLAY INVISIBLE (-1825 2875);
FORCEPROP 2 LAST PATH I226
J 0
(-1900 3050);
DISPLAY 1.021277 (-1900 3050);
DISPLAY INVISIBLE (-1900 3050);
FORCEADD OFFPAGE..1
(-1950 2925);
FORCEPROP 2 LAST $XR0 184 
J 0
(-2202 2925);
DISPLAY 0.638298 (-2202 2925);
PAINT MONO (-2202 2925);
FORCEPROP 2 LAST CDS_LIB standard
J 0
(-1950 2925);
DISPLAY INVISIBLE (-1950 2925);
FORCEPROP 1 LAST OFFPAGE TRUE
J 0
(-1625 2800);
DISPLAY 0.872340 (-1625 2800);
DISPLAY INVISIBLE (-1625 2800);
FORCEPROP 1 LAST COMMENT_BODY TRUE
J 0
(-1825 2825);
DISPLAY 1.170213 (-1825 2825);
PAINT GREEN (-1825 2825);
DISPLAY INVISIBLE (-1825 2825);
FORCEPROP 2 LAST PATH I227
J 0
(-1900 3000);
DISPLAY 1.021277 (-1900 3000);
DISPLAY INVISIBLE (-1900 3000);
FORCEADD OFFPAGE..1
(-1950 2875);
FORCEPROP 2 LAST $XR0 184 
J 0
(-2202 2875);
DISPLAY 0.638298 (-2202 2875);
PAINT MONO (-2202 2875);
FORCEPROP 2 LAST CDS_LIB standard
J 0
(-1950 2875);
DISPLAY INVISIBLE (-1950 2875);
FORCEPROP 1 LAST OFFPAGE TRUE
J 0
(-1625 2750);
DISPLAY 0.872340 (-1625 2750);
DISPLAY INVISIBLE (-1625 2750);
FORCEPROP 1 LAST COMMENT_BODY TRUE
J 0
(-1825 2775);
DISPLAY 1.170213 (-1825 2775);
PAINT GREEN (-1825 2775);
DISPLAY INVISIBLE (-1825 2775);
FORCEPROP 2 LAST PATH I228
J 0
(-1900 2950);
DISPLAY 1.021277 (-1900 2950);
DISPLAY INVISIBLE (-1900 2950);
FORCEADD OFFPAGE..1
(-1950 2825);
FORCEPROP 2 LAST $XR0 184 
J 0
(-2202 2825);
DISPLAY 0.638298 (-2202 2825);
PAINT MONO (-2202 2825);
FORCEPROP 2 LAST CDS_LIB standard
J 0
(-1950 2825);
DISPLAY INVISIBLE (-1950 2825);
FORCEPROP 1 LAST OFFPAGE TRUE
J 0
(-1625 2700);
DISPLAY 0.872340 (-1625 2700);
DISPLAY INVISIBLE (-1625 2700);
FORCEPROP 1 LAST COMMENT_BODY TRUE
J 0
(-1825 2725);
DISPLAY 1.170213 (-1825 2725);
PAINT GREEN (-1825 2725);
DISPLAY INVISIBLE (-1825 2725);
FORCEPROP 2 LAST PATH I229
J 0
(-1900 2900);
DISPLAY 1.021277 (-1900 2900);
DISPLAY INVISIBLE (-1900 2900);
FORCEADD OFFPAGE..1
R 2
(4750 3225);
FORCEPROP 2 LAST $XR0 199 
J 0
(4936 3225);
DISPLAY 0.638298 (4936 3225);
PAINT MONO (4936 3225);
FORCEPROP 2 LAST CDS_LIB standard
J 0
(4750 3225);
PAINT MONO (4750 3225);
DISPLAY INVISIBLE (4750 3225);
FORCEPROP 1 LAST OFFPAGE TRUE
J 2
(4425 3100);
DISPLAY 1.170213 (4425 3100);
PAINT GREEN (4425 3100);
DISPLAY INVISIBLE (4425 3100);
FORCEPROP 1 LAST COMMENT_BODY TRUE
J 2
(4625 3125);
DISPLAY 1.170213 (4625 3125);
PAINT GREEN (4625 3125);
DISPLAY INVISIBLE (4625 3125);
FORCEPROP 2 LAST PATH I23
J 0
(4950 3275);
DISPLAY 1.021277 (4950 3275);
DISPLAY INVISIBLE (4950 3275);
FORCEADD OFFPAGE..1
(-1950 2775);
FORCEPROP 2 LAST $XR0 184 
J 0
(-2202 2775);
DISPLAY 0.638298 (-2202 2775);
PAINT MONO (-2202 2775);
FORCEPROP 2 LAST CDS_LIB standard
J 0
(-1950 2775);
DISPLAY INVISIBLE (-1950 2775);
FORCEPROP 1 LAST OFFPAGE TRUE
J 0
(-1625 2650);
DISPLAY 0.872340 (-1625 2650);
DISPLAY INVISIBLE (-1625 2650);
FORCEPROP 1 LAST COMMENT_BODY TRUE
J 0
(-1825 2675);
DISPLAY 1.170213 (-1825 2675);
PAINT GREEN (-1825 2675);
DISPLAY INVISIBLE (-1825 2675);
FORCEPROP 2 LAST PATH I230
J 0
(-1900 2850);
DISPLAY 1.021277 (-1900 2850);
DISPLAY INVISIBLE (-1900 2850);
FORCEADD OFFPAGE..1
(-1950 2725);
FORCEPROP 2 LAST $XR0 184 
J 0
(-2202 2725);
DISPLAY 0.638298 (-2202 2725);
PAINT MONO (-2202 2725);
FORCEPROP 2 LAST CDS_LIB standard
J 0
(-1950 2725);
DISPLAY INVISIBLE (-1950 2725);
FORCEPROP 1 LAST OFFPAGE TRUE
J 0
(-1625 2600);
DISPLAY 0.872340 (-1625 2600);
DISPLAY INVISIBLE (-1625 2600);
FORCEPROP 1 LAST COMMENT_BODY TRUE
J 0
(-1825 2625);
DISPLAY 1.170213 (-1825 2625);
PAINT GREEN (-1825 2625);
DISPLAY INVISIBLE (-1825 2625);
FORCEPROP 2 LAST PATH I231
J 0
(-1900 2800);
DISPLAY 1.021277 (-1900 2800);
DISPLAY INVISIBLE (-1900 2800);
FORCEADD OFFPAGE..1
(-1950 2675);
FORCEPROP 2 LAST $XR0 184 
J 0
(-2202 2675);
DISPLAY 0.638298 (-2202 2675);
PAINT MONO (-2202 2675);
FORCEPROP 2 LAST CDS_LIB standard
J 0
(-1950 2675);
DISPLAY INVISIBLE (-1950 2675);
FORCEPROP 1 LAST OFFPAGE TRUE
J 0
(-1625 2550);
DISPLAY 0.872340 (-1625 2550);
DISPLAY INVISIBLE (-1625 2550);
FORCEPROP 1 LAST COMMENT_BODY TRUE
J 0
(-1825 2575);
DISPLAY 1.170213 (-1825 2575);
PAINT GREEN (-1825 2575);
DISPLAY INVISIBLE (-1825 2575);
FORCEPROP 2 LAST PATH I232
J 0
(-1900 2750);
DISPLAY 1.021277 (-1900 2750);
DISPLAY INVISIBLE (-1900 2750);
FORCEADD OFFPAGE..1
R 2
(4750 3075);
FORCEPROP 2 LAST $XR0 184 
J 0
(4936 3075);
DISPLAY 0.638298 (4936 3075);
PAINT MONO (4936 3075);
FORCEPROP 2 LAST CDS_LIB standard
J 0
(4750 3075);
DISPLAY INVISIBLE (4750 3075);
FORCEPROP 1 LAST OFFPAGE TRUE
J 2
(4425 2950);
DISPLAY 1.170213 (4425 2950);
PAINT GREEN (4425 2950);
DISPLAY INVISIBLE (4425 2950);
FORCEPROP 1 LAST COMMENT_BODY TRUE
J 2
(4625 2975);
DISPLAY 1.170213 (4625 2975);
PAINT GREEN (4625 2975);
DISPLAY INVISIBLE (4625 2975);
FORCEPROP 2 LAST PATH I233
J 0
(4925 3150);
DISPLAY 1.021277 (4925 3150);
DISPLAY INVISIBLE (4925 3150);
FORCEADD OFFPAGE..1
R 2
(4750 3025);
FORCEPROP 2 LAST $XR0 184 
J 0
(4936 3025);
DISPLAY 0.638298 (4936 3025);
PAINT MONO (4936 3025);
FORCEPROP 2 LAST CDS_LIB standard
J 0
(4750 3025);
DISPLAY INVISIBLE (4750 3025);
FORCEPROP 1 LAST OFFPAGE TRUE
J 2
(4425 2900);
DISPLAY 1.170213 (4425 2900);
PAINT GREEN (4425 2900);
DISPLAY INVISIBLE (4425 2900);
FORCEPROP 1 LAST COMMENT_BODY TRUE
J 2
(4625 2925);
DISPLAY 1.170213 (4625 2925);
PAINT GREEN (4625 2925);
DISPLAY INVISIBLE (4625 2925);
FORCEPROP 2 LAST PATH I234
J 0
(4925 3100);
DISPLAY 1.021277 (4925 3100);
DISPLAY INVISIBLE (4925 3100);
FORCEADD OFFPAGE..1
R 2
(4750 2975);
FORCEPROP 2 LAST $XR0 184 
J 0
(4936 2975);
DISPLAY 0.638298 (4936 2975);
PAINT MONO (4936 2975);
FORCEPROP 2 LAST CDS_LIB standard
J 0
(4750 2975);
DISPLAY INVISIBLE (4750 2975);
FORCEPROP 1 LAST OFFPAGE TRUE
J 2
(4425 2850);
DISPLAY 1.170213 (4425 2850);
PAINT GREEN (4425 2850);
DISPLAY INVISIBLE (4425 2850);
FORCEPROP 1 LAST COMMENT_BODY TRUE
J 2
(4625 2875);
DISPLAY 1.170213 (4625 2875);
PAINT GREEN (4625 2875);
DISPLAY INVISIBLE (4625 2875);
FORCEPROP 2 LAST PATH I235
J 0
(4925 3050);
DISPLAY 1.021277 (4925 3050);
DISPLAY INVISIBLE (4925 3050);
FORCEADD OFFPAGE..1
R 2
(4750 2875);
FORCEPROP 2 LAST $XR0 184 
J 0
(4936 2875);
DISPLAY 0.638298 (4936 2875);
PAINT MONO (4936 2875);
FORCEPROP 2 LAST CDS_LIB standard
J 0
(4750 2875);
DISPLAY INVISIBLE (4750 2875);
FORCEPROP 1 LAST OFFPAGE TRUE
J 2
(4425 2750);
DISPLAY 1.170213 (4425 2750);
PAINT GREEN (4425 2750);
DISPLAY INVISIBLE (4425 2750);
FORCEPROP 1 LAST COMMENT_BODY TRUE
J 2
(4625 2775);
DISPLAY 1.170213 (4625 2775);
PAINT GREEN (4625 2775);
DISPLAY INVISIBLE (4625 2775);
FORCEPROP 2 LAST PATH I237
J 0
(4925 2950);
DISPLAY 1.021277 (4925 2950);
DISPLAY INVISIBLE (4925 2950);
FORCEADD OFFPAGE..1
R 2
(4750 2925);
FORCEPROP 2 LAST $XR0 184 
J 0
(4936 2925);
DISPLAY 0.638298 (4936 2925);
PAINT MONO (4936 2925);
FORCEPROP 2 LAST CDS_LIB standard
J 0
(4750 2925);
DISPLAY INVISIBLE (4750 2925);
FORCEPROP 1 LAST OFFPAGE TRUE
J 2
(4425 2800);
DISPLAY 1.170213 (4425 2800);
PAINT GREEN (4425 2800);
DISPLAY INVISIBLE (4425 2800);
FORCEPROP 1 LAST COMMENT_BODY TRUE
J 2
(4625 2825);
DISPLAY 1.170213 (4625 2825);
PAINT GREEN (4625 2825);
DISPLAY INVISIBLE (4625 2825);
FORCEPROP 2 LAST PATH I238
J 0
(4925 3000);
DISPLAY 1.021277 (4925 3000);
DISPLAY INVISIBLE (4925 3000);
FORCEADD Q_RES..1
(1925 -775);
FORCEPROP 1 LAST PART_NUMBER CS31002FB08
J 0
(1775 -700);
DISPLAY 0.638298 (1775 -700);
DISPLAY INVISIBLE (1775 -700);
FORCEPROP 1 LAST VALUE 10K
J 2
(2125 -775);
DISPLAY 0.638298 (2125 -775);
FORCEPROP 1 LAST MATERIAL CHIP
J 0
(2250 -775);
DISPLAY 0.638298 (2250 -775);
FORCEPROP 1 LAST TOLERANCE 1%
J 0
(2150 -775);
DISPLAY 0.638298 (2150 -775);
FORCEPROP 1 LAST $LOCATION R4564
J 0
(1700 -775);
DISPLAY 0.808511 (1700 -775);
FORCEPROP 1 LASTPIN (1825 -775) $PN 1
J 0
(1837 -763);
DISPLAY 0.787234 (1837 -763);
PAINT MONO (1837 -763);
FORCEPROP 1 LASTPIN (2025 -775) $PN 2
J 0
(1987 -763);
DISPLAY 0.787234 (1987 -763);
PAINT MONO (1987 -763);
FORCEPROP 1 LAST WATTAGE 1/16W
J 2
(2175 -650);
DISPLAY 0.638298 (2175 -650);
DISPLAY INVISIBLE (2175 -650);
FORCEPROP 1 LAST PACK_TYPE 0402LF
J 0
(1775 -650);
DISPLAY 0.638298 (1775 -650);
DISPLAY INVISIBLE (1775 -650);
FORCEPROP 2 LAST CDS_LIB pure_quanta
J 0
(1925 -775);
DISPLAY INVISIBLE (1925 -775);
FORCEPROP 1 LAST PATH I239
J 0
(1875 -625);
DISPLAY 0.978723 (1875 -625);
PAINT WHITE (1875 -625);
DISPLAY INVISIBLE (1875 -625);
FORCEPROP 0 LAST CDS_LOCATION R4564
J 0
(2250 -725);
DISPLAY 1.021277 (2250 -725);
DISPLAY INVISIBLE (2250 -725);
FORCEPROP 0 LAST $SEC 1
J 0
(2250 -725);
DISPLAY 0.680851 (2250 -725);
PAINT MONO (2250 -725);
DISPLAY INVISIBLE (2250 -725);
FORCEPROP 0 LAST CDS_SEC 1
J 0
(2250 -725);
DISPLAY 1.021277 (2250 -725);
DISPLAY INVISIBLE (2250 -725);
FORCEADD OFFPAGE..1
R 2
(4750 3175);
FORCEPROP 2 LAST $XR0 200 
J 0
(4936 3175);
DISPLAY 0.638298 (4936 3175);
PAINT MONO (4936 3175);
FORCEPROP 2 LAST CDS_LIB standard
J 0
(4750 3175);
PAINT MONO (4750 3175);
DISPLAY INVISIBLE (4750 3175);
FORCEPROP 1 LAST OFFPAGE TRUE
J 2
(4425 3050);
DISPLAY 1.170213 (4425 3050);
PAINT GREEN (4425 3050);
DISPLAY INVISIBLE (4425 3050);
FORCEPROP 1 LAST COMMENT_BODY TRUE
J 2
(4625 3075);
DISPLAY 1.170213 (4625 3075);
PAINT GREEN (4625 3075);
DISPLAY INVISIBLE (4625 3075);
FORCEPROP 2 LAST PATH I24
J 0
(4950 3225);
DISPLAY 1.021277 (4950 3225);
DISPLAY INVISIBLE (4950 3225);
FORCEADD Q_RES..1
(1925 -875);
FORCEPROP 1 LAST PART_NUMBER CS31002FB08
J 0
(1775 -800);
DISPLAY 0.638298 (1775 -800);
DISPLAY INVISIBLE (1775 -800);
FORCEPROP 1 LAST MATERIAL CHIP
J 0
(2250 -875);
DISPLAY 0.638298 (2250 -875);
FORCEPROP 1 LAST TOLERANCE 1%
J 0
(2150 -875);
DISPLAY 0.638298 (2150 -875);
FORCEPROP 1 LAST VALUE 10K
J 2
(2125 -875);
DISPLAY 0.638298 (2125 -875);
FORCEPROP 1 LAST $LOCATION R4565
J 0
(1700 -875);
DISPLAY 0.808511 (1700 -875);
FORCEPROP 1 LASTPIN (1825 -875) $PN 1
J 0
(1837 -863);
DISPLAY 0.787234 (1837 -863);
PAINT MONO (1837 -863);
FORCEPROP 1 LASTPIN (2025 -875) $PN 2
J 0
(1987 -863);
DISPLAY 0.787234 (1987 -863);
PAINT MONO (1987 -863);
FORCEPROP 1 LAST PACK_TYPE 0402LF
J 0
(1775 -750);
DISPLAY 0.638298 (1775 -750);
DISPLAY INVISIBLE (1775 -750);
FORCEPROP 1 LAST WATTAGE 1/16W
J 2
(2175 -750);
DISPLAY 0.638298 (2175 -750);
DISPLAY INVISIBLE (2175 -750);
FORCEPROP 2 LAST CDS_LIB pure_quanta
J 0
(1925 -875);
DISPLAY INVISIBLE (1925 -875);
FORCEPROP 1 LAST PATH I240
J 0
(1875 -725);
DISPLAY 0.978723 (1875 -725);
PAINT WHITE (1875 -725);
DISPLAY INVISIBLE (1875 -725);
FORCEPROP 0 LAST CDS_LOCATION R4565
J 0
(2250 -825);
DISPLAY 1.021277 (2250 -825);
DISPLAY INVISIBLE (2250 -825);
FORCEPROP 0 LAST $SEC 1
J 0
(2250 -825);
DISPLAY 0.680851 (2250 -825);
PAINT MONO (2250 -825);
DISPLAY INVISIBLE (2250 -825);
FORCEPROP 0 LAST CDS_SEC 1
J 0
(2250 -825);
DISPLAY 1.021277 (2250 -825);
DISPLAY INVISIBLE (2250 -825);
FORCEADD OFFPAGE..2
R 2
(650 -875);
FORCEPROP 2 LAST $XR0 184 
J 0
(395 -875);
DISPLAY 0.638298 (395 -875);
PAINT MONO (395 -875);
FORCEPROP 2 LAST CDS_LIB standard
J 0
(650 -875);
DISPLAY INVISIBLE (650 -875);
FORCEPROP 1 LAST OFFPAGE TRUE
J 2
(325 -1000);
DISPLAY 0.872340 (325 -1000);
DISPLAY INVISIBLE (325 -1000);
FORCEPROP 1 LAST COMMENT_BODY TRUE
J 2
(695 -970);
DISPLAY 0.872340 (695 -970);
PAINT GREEN (695 -970);
DISPLAY INVISIBLE (695 -970);
FORCEPROP 2 LAST PATH I243
J 0
(700 -800);
DISPLAY 1.021277 (700 -800);
DISPLAY INVISIBLE (700 -800);
FORCEADD OFFPAGE..2
R 2
(650 -775);
FORCEPROP 2 LAST $XR0 184 
J 0
(395 -775);
DISPLAY 0.638298 (395 -775);
PAINT MONO (395 -775);
FORCEPROP 2 LAST CDS_LIB standard
J 0
(650 -775);
DISPLAY INVISIBLE (650 -775);
FORCEPROP 1 LAST OFFPAGE TRUE
J 2
(325 -900);
DISPLAY 0.872340 (325 -900);
DISPLAY INVISIBLE (325 -900);
FORCEPROP 1 LAST COMMENT_BODY TRUE
J 2
(695 -870);
DISPLAY 0.872340 (695 -870);
PAINT GREEN (695 -870);
DISPLAY INVISIBLE (695 -870);
FORCEPROP 2 LAST PATH I244
J 0
(700 -700);
DISPLAY 1.021277 (700 -700);
DISPLAY INVISIBLE (700 -700);
FORCEADD OFFPAGE..2
(4750 2825);
FORCEPROP 2 LAST $XR1 215 
J 0
(5059 2825);
DISPLAY 0.638298 (5059 2825);
PAINT MONO (5059 2825);
FORCEPROP 2 LAST $XR0 184 
J 0
(4939 2825);
DISPLAY 0.638298 (4939 2825);
PAINT MONO (4939 2825);
FORCEPROP 1 LAST OFFPAGE TRUE
J 0
(5075 2700);
DISPLAY 1.170213 (5075 2700);
PAINT GREEN (5075 2700);
DISPLAY INVISIBLE (5075 2700);
FORCEPROP 1 LAST COMMENT_BODY TRUE
J 0
(4705 2730);
DISPLAY 1.170213 (4705 2730);
PAINT GREEN (4705 2730);
DISPLAY INVISIBLE (4705 2730);
FORCEPROP 2 LAST PATH I245
J 0
(4925 2900);
DISPLAY 1.021277 (4925 2900);
DISPLAY INVISIBLE (4925 2900);
FORCEPROP 2 LAST CDS_LIB standard
J 0
(4750 2825);
DISPLAY INVISIBLE (4750 2825);
FORCEADD Q_RES..1
(4675 500);
FORCEPROP 1 LAST PART_NUMBER CS31002FB08
J 0
(4525 575);
DISPLAY 0.638298 (4525 575);
DISPLAY INVISIBLE (4525 575);
FORCEPROP 1 LAST VALUE 10K
J 2
(4875 500);
DISPLAY 0.638298 (4875 500);
FORCEPROP 1 LAST TOLERANCE 1%
J 0
(4900 500);
DISPLAY 0.638298 (4900 500);
FORCEPROP 1 LAST MATERIAL CHIP
J 0
(5000 500);
DISPLAY 0.638298 (5000 500);
FORCEPROP 1 LAST $LOCATION R4722
J 0
(4475 500);
DISPLAY 0.638298 (4475 500);
FORCEPROP 1 LASTPIN (4575 500) $PN 1
J 0
(4587 512);
DISPLAY 0.787234 (4587 512);
PAINT MONO (4587 512);
FORCEPROP 1 LASTPIN (4775 500) $PN 2
J 0
(4737 512);
DISPLAY 0.787234 (4737 512);
PAINT MONO (4737 512);
FORCEPROP 1 LAST PACK_TYPE 0402LF
J 0
(4525 625);
DISPLAY 0.638298 (4525 625);
DISPLAY INVISIBLE (4525 625);
FORCEPROP 1 LAST WATTAGE 1/16W
J 2
(4925 625);
DISPLAY 0.638298 (4925 625);
DISPLAY INVISIBLE (4925 625);
FORCEPROP 1 LAST PATH I246
J 0
(4625 650);
DISPLAY 0.978723 (4625 650);
PAINT WHITE (4625 650);
DISPLAY INVISIBLE (4625 650);
FORCEPROP 2 LAST CDS_LIB pure_quanta
J 0
(4675 500);
DISPLAY INVISIBLE (4675 500);
FORCEPROP 0 LAST CDS_LOCATION R4722
J 0
(5000 550);
DISPLAY 1.021277 (5000 550);
DISPLAY INVISIBLE (5000 550);
FORCEPROP 0 LAST $SEC 1
J 0
(5000 550);
DISPLAY 0.680851 (5000 550);
PAINT MONO (5000 550);
DISPLAY INVISIBLE (5000 550);
FORCEPROP 0 LAST CDS_SEC 1
J 0
(5000 550);
DISPLAY 1.021277 (5000 550);
DISPLAY INVISIBLE (5000 550);
FORCEADD UNIVERSAL_POWER..1
(5225 850);
FORCEPROP 3 LASTPIN (5225 800) SIG_NAME P3V3_AUX\g
J 0
(5235 810);
DISPLAY 0.659574 (5235 810);
PAINT MONO (5235 810);
DISPLAY INVISIBLE (5235 810);
FORCEPROP 1 LAST HDL_POWER P3V3_AUX
J 1
(5225 900);
DISPLAY 0.872340 (5225 900);
PAINT GREEN (5225 900);
FORCEPROP 1 LAST PATH I247
J 0
(5275 875);
DISPLAY 0.872340 (5275 875);
PAINT AQUA (5275 875);
DISPLAY INVISIBLE (5275 875);
FORCEPROP 2 LAST CDS_LIB logical_power
J 0
(5225 850);
DISPLAY INVISIBLE (5225 850);
FORCEADD OFFPAGE..2
R 2
(3725 500);
FORCEPROP 2 LAST $XR1 215 
J 0
(3440 464);
DISPLAY 0.638298 (3440 464);
PAINT MONO (3440 464);
FORCEPROP 2 LAST $XR0 184 
J 0
(3440 500);
DISPLAY 0.638298 (3440 500);
PAINT MONO (3440 500);
FORCEPROP 2 LAST CDS_LIB standard
J 2
(3725 500);
DISPLAY INVISIBLE (3725 500);
FORCEPROP 2 LAST PATH I248
J 2
(3550 575);
DISPLAY 1.021277 (3550 575);
DISPLAY INVISIBLE (3550 575);
FORCEPROP 1 LAST OFFPAGE TRUE
J 2
(3400 375);
DISPLAY 1.170213 (3400 375);
PAINT GREEN (3400 375);
DISPLAY INVISIBLE (3400 375);
FORCEPROP 1 LAST COMMENT_BODY TRUE
J 2
(3770 405);
DISPLAY 1.170213 (3770 405);
PAINT GREEN (3770 405);
DISPLAY INVISIBLE (3770 405);
FORCEADD OFFPAGE..1
R 2
(4750 3125);
FORCEPROP 2 LAST $XR1 215 
J 0
(5056 3125);
DISPLAY 0.638298 (5056 3125);
PAINT MONO (5056 3125);
FORCEPROP 2 LAST $XR0 204 
J 0
(4936 3125);
DISPLAY 0.638298 (4936 3125);
PAINT MONO (4936 3125);
FORCEPROP 2 LAST CDS_LIB standard
J 0
(4750 3125);
PAINT MONO (4750 3125);
DISPLAY INVISIBLE (4750 3125);
FORCEPROP 1 LAST OFFPAGE TRUE
J 2
(4425 3000);
DISPLAY 1.170213 (4425 3000);
PAINT GREEN (4425 3000);
DISPLAY INVISIBLE (4425 3000);
FORCEPROP 1 LAST COMMENT_BODY TRUE
J 2
(4625 3025);
DISPLAY 1.170213 (4625 3025);
PAINT GREEN (4625 3025);
DISPLAY INVISIBLE (4625 3025);
FORCEPROP 2 LAST PATH I25
J 0
(4950 3175);
DISPLAY 1.021277 (4950 3175);
DISPLAY INVISIBLE (4950 3175);
FORCEADD OFFPAGE..1
R 2
(4750 2025);
FORCEPROP 2 LAST $XR0 201 
J 0
(4936 2025);
DISPLAY 0.638298 (4936 2025);
PAINT MONO (4936 2025);
FORCEPROP 2 LAST CDS_LIB standard
J 0
(4750 2025);
PAINT MONO (4750 2025);
DISPLAY INVISIBLE (4750 2025);
FORCEPROP 1 LAST OFFPAGE TRUE
J 2
(4425 1900);
DISPLAY 1.170213 (4425 1900);
PAINT GREEN (4425 1900);
DISPLAY INVISIBLE (4425 1900);
FORCEPROP 1 LAST COMMENT_BODY TRUE
J 2
(4625 1925);
DISPLAY 1.170213 (4625 1925);
PAINT GREEN (4625 1925);
DISPLAY INVISIBLE (4625 1925);
FORCEPROP 2 LAST PATH I26
J 0
(4950 2075);
DISPLAY 1.021277 (4950 2075);
DISPLAY INVISIBLE (4950 2075);
FORCEADD OFFPAGE..1
R 2
(4750 1675);
FORCEPROP 2 LAST $XR0 195 
J 0
(4936 1675);
DISPLAY 0.638298 (4936 1675);
PAINT MONO (4936 1675);
FORCEPROP 2 LAST CDS_LIB standard
J 0
(4750 1675);
PAINT MONO (4750 1675);
DISPLAY INVISIBLE (4750 1675);
FORCEPROP 1 LAST OFFPAGE TRUE
J 2
(4425 1550);
DISPLAY 1.170213 (4425 1550);
PAINT GREEN (4425 1550);
DISPLAY INVISIBLE (4425 1550);
FORCEPROP 1 LAST COMMENT_BODY TRUE
J 2
(4625 1575);
DISPLAY 1.170213 (4625 1575);
PAINT GREEN (4625 1575);
DISPLAY INVISIBLE (4625 1575);
FORCEPROP 2 LAST PATH I31
J 0
(4950 1725);
DISPLAY 1.021277 (4950 1725);
DISPLAY INVISIBLE (4950 1725);
FORCEADD OFFPAGE..1
R 2
(4750 1725);
FORCEPROP 2 LAST $XR0 195 
J 0
(4936 1725);
DISPLAY 0.638298 (4936 1725);
PAINT MONO (4936 1725);
FORCEPROP 2 LAST CDS_LIB standard
J 0
(4750 1725);
PAINT MONO (4750 1725);
DISPLAY INVISIBLE (4750 1725);
FORCEPROP 1 LAST OFFPAGE TRUE
J 2
(4425 1600);
DISPLAY 1.170213 (4425 1600);
PAINT GREEN (4425 1600);
DISPLAY INVISIBLE (4425 1600);
FORCEPROP 1 LAST COMMENT_BODY TRUE
J 2
(4625 1625);
DISPLAY 1.170213 (4625 1625);
PAINT GREEN (4625 1625);
DISPLAY INVISIBLE (4625 1625);
FORCEPROP 2 LAST PATH I32
J 0
(4950 1775);
DISPLAY 1.021277 (4950 1775);
DISPLAY INVISIBLE (4950 1775);
FORCEADD OFFPAGE..1
R 2
(4750 1775);
FORCEPROP 2 LAST $XR0 195 
J 0
(4936 1775);
DISPLAY 0.638298 (4936 1775);
PAINT MONO (4936 1775);
FORCEPROP 2 LAST CDS_LIB standard
J 0
(4750 1775);
PAINT MONO (4750 1775);
DISPLAY INVISIBLE (4750 1775);
FORCEPROP 1 LAST OFFPAGE TRUE
J 2
(4425 1650);
DISPLAY 1.170213 (4425 1650);
PAINT GREEN (4425 1650);
DISPLAY INVISIBLE (4425 1650);
FORCEPROP 1 LAST COMMENT_BODY TRUE
J 2
(4625 1675);
DISPLAY 1.170213 (4625 1675);
PAINT GREEN (4625 1675);
DISPLAY INVISIBLE (4625 1675);
FORCEPROP 2 LAST PATH I34
J 0
(4950 1825);
DISPLAY 1.021277 (4950 1825);
DISPLAY INVISIBLE (4950 1825);
FORCEADD OFFPAGE..1
R 2
(4750 2625);
FORCEPROP 2 LAST $XR0 200 
J 0
(4936 2625);
DISPLAY 0.638298 (4936 2625);
PAINT MONO (4936 2625);
FORCEPROP 2 LAST CDS_LIB standard
J 0
(4750 2625);
PAINT MONO (4750 2625);
DISPLAY INVISIBLE (4750 2625);
FORCEPROP 1 LAST OFFPAGE TRUE
J 2
(4425 2500);
DISPLAY 1.170213 (4425 2500);
PAINT GREEN (4425 2500);
DISPLAY INVISIBLE (4425 2500);
FORCEPROP 1 LAST COMMENT_BODY TRUE
J 2
(4625 2525);
DISPLAY 1.170213 (4625 2525);
PAINT GREEN (4625 2525);
DISPLAY INVISIBLE (4625 2525);
FORCEPROP 2 LAST PATH I39
J 0
(4950 2675);
DISPLAY 1.021277 (4950 2675);
DISPLAY INVISIBLE (4950 2675);
FORCEADD OFFPAGE..1
R 2
(4750 2525);
FORCEPROP 2 LAST $XR0 201 
J 0
(4936 2525);
DISPLAY 0.638298 (4936 2525);
PAINT MONO (4936 2525);
FORCEPROP 2 LAST CDS_LIB standard
J 0
(4750 2525);
PAINT MONO (4750 2525);
DISPLAY INVISIBLE (4750 2525);
FORCEPROP 1 LAST OFFPAGE TRUE
J 2
(4425 2400);
DISPLAY 1.170213 (4425 2400);
PAINT GREEN (4425 2400);
DISPLAY INVISIBLE (4425 2400);
FORCEPROP 1 LAST COMMENT_BODY TRUE
J 2
(4625 2425);
DISPLAY 1.170213 (4625 2425);
PAINT GREEN (4625 2425);
DISPLAY INVISIBLE (4625 2425);
FORCEPROP 2 LAST PATH I40
J 0
(4950 2575);
DISPLAY 1.021277 (4950 2575);
DISPLAY INVISIBLE (4950 2575);
FORCEADD OFFPAGE..1
R 2
(4750 2575);
FORCEPROP 2 LAST $XR0 201 
J 0
(4936 2575);
DISPLAY 0.638298 (4936 2575);
PAINT MONO (4936 2575);
FORCEPROP 2 LAST CDS_LIB standard
J 0
(4750 2575);
PAINT MONO (4750 2575);
DISPLAY INVISIBLE (4750 2575);
FORCEPROP 1 LAST OFFPAGE TRUE
J 2
(4425 2450);
DISPLAY 1.170213 (4425 2450);
PAINT GREEN (4425 2450);
DISPLAY INVISIBLE (4425 2450);
FORCEPROP 1 LAST COMMENT_BODY TRUE
J 2
(4625 2475);
DISPLAY 1.170213 (4625 2475);
PAINT GREEN (4625 2475);
DISPLAY INVISIBLE (4625 2475);
FORCEPROP 2 LAST PATH I41
J 0
(4950 2625);
DISPLAY 1.021277 (4950 2625);
DISPLAY INVISIBLE (4950 2625);
FORCEADD OFFPAGE..1
(-1950 2175);
FORCEPROP 2 LAST $XR0 199 
J 0
(-2202 2175);
DISPLAY 0.638298 (-2202 2175);
PAINT MONO (-2202 2175);
FORCEPROP 2 LAST CDS_LIB standard
J 0
(-1950 2175);
PAINT MONO (-1950 2175);
DISPLAY INVISIBLE (-1950 2175);
FORCEPROP 1 LAST OFFPAGE TRUE
J 0
(-1625 2050);
DISPLAY 0.872340 (-1625 2050);
DISPLAY INVISIBLE (-1625 2050);
FORCEPROP 1 LAST COMMENT_BODY TRUE
J 0
(-1825 2075);
DISPLAY 1.170213 (-1825 2075);
PAINT GREEN (-1825 2075);
DISPLAY INVISIBLE (-1825 2075);
FORCEPROP 2 LAST PATH I42
J 0
(-1900 2250);
DISPLAY 1.021277 (-1900 2250);
DISPLAY INVISIBLE (-1900 2250);
FORCEADD OFFPAGE..1
(-1950 2075);
FORCEPROP 2 LAST $XR0 200 
J 0
(-2202 2075);
DISPLAY 0.638298 (-2202 2075);
PAINT MONO (-2202 2075);
FORCEPROP 2 LAST CDS_LIB standard
J 0
(-1950 2075);
PAINT MONO (-1950 2075);
DISPLAY INVISIBLE (-1950 2075);
FORCEPROP 1 LAST OFFPAGE TRUE
J 0
(-1625 1950);
DISPLAY 0.872340 (-1625 1950);
DISPLAY INVISIBLE (-1625 1950);
FORCEPROP 1 LAST COMMENT_BODY TRUE
J 0
(-1825 1975);
DISPLAY 1.170213 (-1825 1975);
PAINT GREEN (-1825 1975);
DISPLAY INVISIBLE (-1825 1975);
FORCEPROP 2 LAST PATH I43
J 0
(-1900 2150);
DISPLAY 1.021277 (-1900 2150);
DISPLAY INVISIBLE (-1900 2150);
FORCEADD OFFPAGE..1
(-1950 2025);
FORCEPROP 2 LAST $XR0 200 
J 0
(-2202 2025);
DISPLAY 0.638298 (-2202 2025);
PAINT MONO (-2202 2025);
FORCEPROP 2 LAST CDS_LIB standard
J 0
(-1950 2025);
PAINT MONO (-1950 2025);
DISPLAY INVISIBLE (-1950 2025);
FORCEPROP 1 LAST OFFPAGE TRUE
J 0
(-1625 1900);
DISPLAY 0.872340 (-1625 1900);
DISPLAY INVISIBLE (-1625 1900);
FORCEPROP 1 LAST COMMENT_BODY TRUE
J 0
(-1825 1925);
DISPLAY 1.170213 (-1825 1925);
PAINT GREEN (-1825 1925);
DISPLAY INVISIBLE (-1825 1925);
FORCEPROP 2 LAST PATH I44
J 0
(-1900 2100);
DISPLAY 1.021277 (-1900 2100);
DISPLAY INVISIBLE (-1900 2100);
FORCEADD OFFPAGE..1
(-1950 1925);
FORCEPROP 2 LAST $XR0 200 
J 0
(-2202 1925);
DISPLAY 0.638298 (-2202 1925);
PAINT MONO (-2202 1925);
FORCEPROP 2 LAST CDS_LIB standard
J 0
(-1950 1925);
PAINT MONO (-1950 1925);
DISPLAY INVISIBLE (-1950 1925);
FORCEPROP 1 LAST OFFPAGE TRUE
J 0
(-1625 1800);
DISPLAY 0.872340 (-1625 1800);
DISPLAY INVISIBLE (-1625 1800);
FORCEPROP 1 LAST COMMENT_BODY TRUE
J 0
(-1825 1825);
DISPLAY 1.170213 (-1825 1825);
PAINT GREEN (-1825 1825);
DISPLAY INVISIBLE (-1825 1825);
FORCEPROP 2 LAST PATH I46
J 0
(-1900 2000);
DISPLAY 1.021277 (-1900 2000);
DISPLAY INVISIBLE (-1900 2000);
FORCEADD OFFPAGE..5
(-1950 3075);
FORCEPROP 2 LAST $XR1 215 
J 0
(-2325 3075);
DISPLAY 0.638298 (-2325 3075);
PAINT MONO (-2325 3075);
FORCEPROP 2 LAST $XR0 204 
J 0
(-2205 3075);
DISPLAY 0.638298 (-2205 3075);
PAINT MONO (-2205 3075);
FORCEPROP 2 LAST CDS_LIB standard
J 0
(-1950 3075);
PAINT MONO (-1950 3075);
DISPLAY INVISIBLE (-1950 3075);
FORCEPROP 1 LAST OFFPAGE TRUE
J 0
(-1625 2950);
DISPLAY 0.872340 (-1625 2950);
DISPLAY INVISIBLE (-1625 2950);
FORCEPROP 1 LAST COMMENT_BODY TRUE
J 0
(-1850 3000);
DISPLAY 1.170213 (-1850 3000);
PAINT GREEN (-1850 3000);
DISPLAY INVISIBLE (-1850 3000);
FORCEPROP 2 LAST PATH I47
J 0
(-2225 3125);
DISPLAY 1.021277 (-2225 3125);
DISPLAY INVISIBLE (-2225 3125);
FORCEADD OFFPAGE..5
(-1950 3025);
FORCEPROP 2 LAST $XR1 215 
J 0
(-2325 3025);
DISPLAY 0.638298 (-2325 3025);
PAINT MONO (-2325 3025);
FORCEPROP 2 LAST $XR0 204 
J 0
(-2205 3025);
DISPLAY 0.638298 (-2205 3025);
PAINT MONO (-2205 3025);
FORCEPROP 2 LAST CDS_LIB standard
J 0
(-1950 3025);
PAINT MONO (-1950 3025);
DISPLAY INVISIBLE (-1950 3025);
FORCEPROP 1 LAST OFFPAGE TRUE
J 0
(-1625 2900);
DISPLAY 0.872340 (-1625 2900);
DISPLAY INVISIBLE (-1625 2900);
FORCEPROP 1 LAST COMMENT_BODY TRUE
J 0
(-1850 2950);
DISPLAY 1.170213 (-1850 2950);
PAINT GREEN (-1850 2950);
DISPLAY INVISIBLE (-1850 2950);
FORCEPROP 2 LAST PATH I48
J 0
(-2225 3075);
DISPLAY 1.021277 (-2225 3075);
DISPLAY INVISIBLE (-2225 3075);
FORCEADD OFFPAGE..1
R 2
(4750 1825);
FORCEPROP 2 LAST $XR0 195 
J 0
(4936 1825);
DISPLAY 0.638298 (4936 1825);
PAINT MONO (4936 1825);
FORCEPROP 2 LAST CDS_LIB standard
J 0
(4750 1825);
PAINT MONO (4750 1825);
DISPLAY INVISIBLE (4750 1825);
FORCEPROP 1 LAST OFFPAGE TRUE
J 2
(4425 1700);
DISPLAY 1.170213 (4425 1700);
PAINT GREEN (4425 1700);
DISPLAY INVISIBLE (4425 1700);
FORCEPROP 1 LAST COMMENT_BODY TRUE
J 2
(4625 1725);
DISPLAY 1.170213 (4625 1725);
PAINT GREEN (4625 1725);
DISPLAY INVISIBLE (4625 1725);
FORCEPROP 2 LAST PATH I53
J 0
(4950 1875);
DISPLAY 1.021277 (4950 1875);
DISPLAY INVISIBLE (4950 1875);
FORCEADD OFFPAGE..1
(-1950 2125);
FORCEPROP 2 LAST $XR0 204 
J 0
(-2202 2125);
DISPLAY 0.638298 (-2202 2125);
PAINT MONO (-2202 2125);
FORCEPROP 2 LAST CDS_LIB standard
J 0
(-1950 2125);
DISPLAY INVISIBLE (-1950 2125);
FORCEPROP 1 LAST OFFPAGE TRUE
J 0
(-1625 2000);
DISPLAY 0.872340 (-1625 2000);
DISPLAY INVISIBLE (-1625 2000);
FORCEPROP 1 LAST COMMENT_BODY TRUE
J 0
(-1825 2025);
DISPLAY 1.170213 (-1825 2025);
PAINT GREEN (-1825 2025);
DISPLAY INVISIBLE (-1825 2025);
FORCEPROP 2 LAST PATH I75
J 0
(-2250 2175);
DISPLAY 1.021277 (-2250 2175);
DISPLAY INVISIBLE (-2250 2175);
FORCEADD OFFPAGE..1
R 2
(4750 2475);
FORCEPROP 2 LAST $XR0 200 
J 0
(4936 2475);
DISPLAY 0.638298 (4936 2475);
PAINT MONO (4936 2475);
FORCEPROP 2 LAST CDS_LIB standard
J 0
(4750 2475);
DISPLAY INVISIBLE (4750 2475);
FORCEPROP 1 LAST OFFPAGE TRUE
J 2
(4425 2350);
DISPLAY 1.170213 (4425 2350);
PAINT GREEN (4425 2350);
DISPLAY INVISIBLE (4425 2350);
FORCEPROP 1 LAST COMMENT_BODY TRUE
J 2
(4625 2375);
DISPLAY 1.170213 (4625 2375);
PAINT GREEN (4625 2375);
DISPLAY INVISIBLE (4625 2375);
FORCEPROP 2 LAST PATH I76
J 0
(4950 2525);
DISPLAY 1.021277 (4950 2525);
DISPLAY INVISIBLE (4950 2525);
FORCEADD OFFPAGE..1
R 2
(4750 1575);
FORCEPROP 2 LAST $XR0 195 
J 0
(4936 1575);
DISPLAY 0.638298 (4936 1575);
PAINT MONO (4936 1575);
FORCEPROP 2 LAST CDS_LIB standard
J 0
(4750 1575);
PAINT MONO (4750 1575);
DISPLAY INVISIBLE (4750 1575);
FORCEPROP 1 LAST OFFPAGE TRUE
J 2
(4425 1450);
DISPLAY 1.170213 (4425 1450);
PAINT GREEN (4425 1450);
DISPLAY INVISIBLE (4425 1450);
FORCEPROP 1 LAST COMMENT_BODY TRUE
J 2
(4625 1475);
DISPLAY 1.170213 (4625 1475);
PAINT GREEN (4625 1475);
DISPLAY INVISIBLE (4625 1475);
FORCEPROP 2 LAST PATH I94
J 0
(5100 1625);
DISPLAY 1.021277 (5100 1625);
DISPLAY INVISIBLE (5100 1625);
FORCEADD OFFPAGE..1
R 2
(4750 1625);
FORCEPROP 2 LAST $XR0 195 
J 0
(4936 1625);
DISPLAY 0.638298 (4936 1625);
PAINT MONO (4936 1625);
FORCEPROP 2 LAST CDS_LIB standard
J 0
(4750 1625);
PAINT MONO (4750 1625);
DISPLAY INVISIBLE (4750 1625);
FORCEPROP 1 LAST OFFPAGE TRUE
J 2
(4425 1500);
DISPLAY 1.170213 (4425 1500);
PAINT GREEN (4425 1500);
DISPLAY INVISIBLE (4425 1500);
FORCEPROP 1 LAST COMMENT_BODY TRUE
J 2
(4625 1525);
DISPLAY 1.170213 (4625 1525);
PAINT GREEN (4625 1525);
DISPLAY INVISIBLE (4625 1525);
FORCEPROP 2 LAST PATH I95
J 0
(4925 1700);
DISPLAY 1.021277 (4925 1700);
DISPLAY INVISIBLE (4925 1700);
FORCEADD DESIGN_NOTE..1
(-2300 -350);
FORCEPROP 2 LAST CDS_LIB logical_power
J 0
(-2300 -350);
DISPLAY INVISIBLE (-2300 -350);
FORCEPROP 1 LAST COMMENT_BODY TRUE
J 0
(-2275 -250);
DISPLAY 0.978723 (-2275 -250);
DISPLAY INVISIBLE (-2275 -250);
FORCEADD DNS..2
(-2475 125);
PAINT RED (-2475 125);
FORCEPROP 2 LAST CDS_LIB mstr_misc
J 0
(-2475 125);
PAINT MONO (-2475 125);
DISPLAY INVISIBLE (-2475 125);
FORCEPROP 1 LAST COMMENT_BODY TRUE
J 0
(-2475 125);
DISPLAY INVISIBLE (-2475 125);
FORCEADD DNS..2
(-2475 775);
PAINT RED (-2475 775);
FORCEPROP 2 LAST CDS_LIB mstr_misc
J 0
(-2475 775);
DISPLAY INVISIBLE (-2475 775);
FORCEPROP 1 LAST COMMENT_BODY TRUE
J 0
(-2475 775);
DISPLAY INVISIBLE (-2475 775);
FORCEADD DNS..2
(-2195 770);
PAINT RED (-2195 770);
FORCEPROP 2 LAST CDS_LIB mstr_misc
J 0
(-2195 770);
DISPLAY INVISIBLE (-2195 770);
FORCEPROP 1 LAST COMMENT_BODY TRUE
J 0
(-2195 770);
DISPLAY INVISIBLE (-2195 770);
FORCEADD DNS..2
(-2200 125);
PAINT RED (-2200 125);
FORCEPROP 2 LAST CDS_LIB mstr_misc
J 0
(-2200 125);
DISPLAY INVISIBLE (-2200 125);
FORCEPROP 1 LAST COMMENT_BODY TRUE
J 0
(-2200 125);
DISPLAY INVISIBLE (-2200 125);
FORCEADD QUANTA_TITLE_BLOCK_C..1
(5950 -2250);
FORCEPROP 0 LAST CDS_CON_LAST_MODIFIED Fri Aug 25 14:02:56 2023
J 0
(4065 -2235);
PAINT MONO (4065 -2235);
DISPLAY INVISIBLE (4065 -2235);
FORCEPROP 1 LAST CUSTOM_TXT_CDS <CON_LAST_MODIFIED>
J 0
(4065 -2235);
DISPLAY 0.978723 (4065 -2235);
FORCEPROP 2 LAST CUSTOM_TXT_CDS <XR_PAGE_TITLE>
J 0
(-1940 3000);
DISPLAY 0.638298 (-1940 3000);
PAINT PINK (-1940 3000);
DISPLAY INVISIBLE (-1940 3000);
FORCEPROP 2 LAST CUSTOM_TXT_CDS <Q_NUMBER>
J 0
(4547 -2147);
DISPLAY 1.212766 (4547 -2147);
FORCEPROP 1 LAST CUSTOM_TXT_CDS <NAME_2>
J 0
(2775 -2200);
FORCEPROP 1 LAST CUSTOM_TXT_CDS <NAME_1>
J 0
(2775 -2075);
FORCEPROP 1 LAST CUSTOM_TXT_CDS <Q_PROJ>
J 0
(3568 -2148);
DISPLAY 1.212766 (3568 -2148);
FORCEPROP 1 LAST CUSTOM_TXT_CDS <Q_REV>
J 0
(5766 -2147);
DISPLAY 1.212766 (5766 -2147);
FORCEPROP 1 LAST CUSTOM_TXT_CDS <CON_PAGE_NUM> OF <CON_TOTAL_PAGES>
J 0
(5504 -2232);
DISPLAY 0.978723 (5504 -2232);
FORCEPROP 1 LAST Q_TITLE EMMITSBURG - GPIO/JTAG (6/10)
J 0
(-3366 -2224);
DISPLAY 1.957447 (-3366 -2224);
PAINT GREEN (-3366 -2224);
FORCEPROP 1 LAST Q_DEPT 
J 1
(2187 -2201);
DISPLAY 1.957447 (2187 -2201);
PAINT GREEN (2187 -2201);
FORCEPROP 2 LAST CDS_XR_PAGE_TITLE CR-184 : @S9S_MB_2U_LIB.S9S_MB_2U(SCH_1):PAGE184
J 0
(-1940 3000);
DISPLAY 0.638298 (-1940 3000);
PAINT PINK (-1940 3000);
DISPLAY INVISIBLE (-1940 3000);
FORCEPROP 1 LAST COMMENT_BODY TRUE
J 0
(5962 -2263);
DISPLAY 0.978723 (5962 -2263);
PAINT GREEN (5962 -2263);
DISPLAY INVISIBLE (5962 -2263);
FORCEPROP 1 LAST CDS_LMAN_SYM_OUTLINE -9475,6775,100,-125
J 0
(5950 -2250);
DISPLAY 0.468085 (5950 -2250);
PAINT GREEN (5950 -2250);
DISPLAY INVISIBLE (5950 -2250);
FORCEPROP 2 LAST CDS_LIB pure_quanta
J 0
(5950 -2250);
PAINT MONO (5950 -2250);
DISPLAY INVISIBLE (5950 -2250);
FORCEPROP 2 LAST PAGE_BORDER TRUE
J 0
(-1940 3000);
DISPLAY 0.638298 (-1940 3000);
PAINT PINK (-1940 3000);
DISPLAY INVISIBLE (-1940 3000);
WIRE 16 -1 (5225 500)(5225 800);
WIRE 16 -1 (4775 500)(5225 500);
WIRE 16 -1 (-2475 1050)(-2475 1125);
WIRE 16 -1 (-2475 1050)(-2200 1050);
WIRE 16 -1 (-2475 900)(-2475 1050);
WIRE 16 -1 (2450 -1025)(2450 -875);
WIRE 16 -1 (-2475 -25)(-2475 50);
WIRE 16 -1 (-2200 -25)(-2200 50);
WIRE 16 2175 (3325 950)(5450 950);
WIRE 16 2175 (5450 950)(5450 400);
WIRE 16 2175 (3325 950)(3325 400);
WIRE 16 2175 (3325 400)(5450 400);
WIRE 16 2175 (300 -1250)(2575 -1250);
WIRE 16 2175 (2575 825)(2575 -1250);
WIRE 16 2175 (300 825)(300 -1250);
WIRE 16 2175 (300 825)(2575 825);
WIRE 16 -1 (3775 500)(4575 500);
FORCEPROP 0 LAST CDS_PHYS_NET_NAME TP_PCH_GPP_L_8
J 0
(3925 541);
PAINT MONO (3925 541);
DISPLAY INVISIBLE (3925 541);
FORCEPROP 2 LAST SIG_NAME FM_PCH_BMC_RST_R_N
J 0
(3840 510);
DISPLAY 0.659574 (3840 510);
PAINT WHITE (3840 510);
WIRE 16 -1 (700 -875)(1825 -875);
FORCEPROP 0 LAST CDS_PHYS_NET_NAME OCP_SFF_BIF1_N
J 0
(850 -834);
PAINT MONO (850 -834);
DISPLAY INVISIBLE (850 -834);
FORCEPROP 2 LAST SIG_NAME PD_GPP_I_13
J 0
(925 -865);
DISPLAY 0.659574 (925 -865);
PAINT WHITE (925 -865);
WIRE 16 -1 (700 325)(1825 325);
FORCEPROP 0 LAST CDS_PHYS_NET_NAME OCP_LFF_4CP_BIF0_N
J 0
(850 366);
PAINT MONO (850 366);
DISPLAY INVISIBLE (850 366);
FORCEPROP 2 LAST SIG_NAME PD_GPP_I_17
J 0
(925 335);
DISPLAY 0.659574 (925 335);
PAINT WHITE (925 335);
WIRE 16 -1 (700 525)(1825 525);
FORCEPROP 0 LAST CDS_PHYS_NET_NAME FM_PCIE_EDSFF4A_PRSNT_1_N
J 0
(925 566);
PAINT MONO (925 566);
DISPLAY INVISIBLE (925 566);
FORCEPROP 2 LAST SIG_NAME PD_GPP_M_15
J 0
(925 535);
DISPLAY 0.659574 (925 535);
PAINT WHITE (925 535);
WIRE 16 -1 (700 625)(1825 625);
FORCEPROP 0 LAST CDS_PHYS_NET_NAME RISER2_TYPE_ID1
J 0
(925 666);
PAINT MONO (925 666);
DISPLAY INVISIBLE (925 666);
FORCEPROP 2 LAST SIG_NAME PD_GPP_M_16
J 0
(925 635);
DISPLAY 0.659574 (925 635);
PAINT WHITE (925 635);
WIRE 16 -1 (700 725)(1825 725);
FORCEPROP 0 LAST CDS_PHYS_NET_NAME RISER2_TYPE_ID1
J 0
(925 766);
PAINT MONO (925 766);
DISPLAY INVISIBLE (925 766);
FORCEPROP 2 LAST SIG_NAME PD_GPP_M_17
J 0
(925 735);
DISPLAY 0.659574 (925 735);
PAINT WHITE (925 735);
WIRE 16 -1 (2025 725)(2450 725);
WIRE 16 -1 (2025 625)(2450 625);
WIRE 16 -1 (2450 725)(2450 625);
WIRE 16 -1 (2025 525)(2450 525);
WIRE 16 -1 (2450 625)(2450 525);
WIRE 16 -1 (2025 425)(2450 425);
WIRE 16 -1 (2450 525)(2450 425);
WIRE 16 -1 (2025 325)(2450 325);
WIRE 16 -1 (2450 425)(2450 325);
WIRE 16 -1 (2025 225)(2450 225);
WIRE 16 -1 (2450 325)(2450 225);
WIRE 16 -1 (2025 125)(2450 125);
WIRE 16 -1 (2450 225)(2450 125);
WIRE 16 -1 (2025 25)(2450 25);
WIRE 16 -1 (2450 125)(2450 25);
WIRE 16 -1 (2025 -75)(2450 -75);
WIRE 16 -1 (2450 25)(2450 -75);
WIRE 16 -1 (2025 -175)(2450 -175);
WIRE 16 -1 (2450 -75)(2450 -175);
WIRE 16 -1 (2025 -275)(2450 -275);
WIRE 16 -1 (2450 -175)(2450 -275);
WIRE 16 -1 (2025 -375)(2450 -375);
WIRE 16 -1 (2450 -275)(2450 -375);
WIRE 16 -1 (2025 -475)(2450 -475);
WIRE 16 -1 (2450 -375)(2450 -475);
WIRE 16 -1 (2025 -575)(2450 -575);
WIRE 16 -1 (2450 -475)(2450 -575);
WIRE 16 -1 (2025 -675)(2450 -675);
WIRE 16 -1 (2450 -675)(2450 -575);
WIRE 16 -1 (2025 -775)(2450 -775);
WIRE 16 -1 (2450 -675)(2450 -775);
WIRE 16 -1 (2450 -775)(2450 -875);
WIRE 16 -1 (2025 -875)(2450 -875);
WIRE 16 -1 (3575 1575)(4700 1575);
FORCEPROP 0 LAST CDS_PHYS_NET_NAME RISER2_TYPE_ID
J 0
(3800 1616);
PAINT MONO (3800 1616);
DISPLAY INVISIBLE (3800 1616);
FORCEPROP 2 LAST SIG_NAME FAB_REV_ID0
J 0
(3800 1585);
DISPLAY 0.659574 (3800 1585);
PAINT WHITE (3800 1585);
WIRE 16 -1 (3575 1625)(4700 1625);
FORCEPROP 0 LAST CDS_PHYS_NET_NAME PCIE_RISER2_PRSNT2_N
J 0
(3800 1666);
PAINT MONO (3800 1666);
DISPLAY INVISIBLE (3800 1666);
FORCEPROP 2 LAST SIG_NAME FAB_REV_ID1
J 0
(3800 1635);
DISPLAY 0.659574 (3800 1635);
PAINT WHITE (3800 1635);
WIRE 16 -1 (3575 1675)(4700 1675);
FORCEPROP 0 LAST CDS_PHYS_NET_NAME RISER2_TYPE_ID
J 0
(3800 1716);
PAINT MONO (3800 1716);
DISPLAY INVISIBLE (3800 1716);
FORCEPROP 2 LAST SIG_NAME FAB_REV_ID2
J 0
(3800 1685);
DISPLAY 0.659574 (3800 1685);
PAINT WHITE (3800 1685);
WIRE 16 -1 (3575 1775)(4700 1775);
FORCEPROP 0 LAST CDS_PHYS_NET_NAME RISER3_TYPE_ID
J 0
(3800 1816);
PAINT MONO (3800 1816);
DISPLAY INVISIBLE (3800 1816);
FORCEPROP 2 LAST SIG_NAME FM_BOARD_SKU_ID1
J 0
(3800 1785);
DISPLAY 0.659574 (3800 1785);
PAINT WHITE (3800 1785);
WIRE 16 -1 (3575 1825)(4700 1825);
FORCEPROP 0 LAST CDS_PHYS_NET_NAME RISER2_TYPE_ID1
J 0
(3800 1866);
PAINT MONO (3800 1866);
DISPLAY INVISIBLE (3800 1866);
FORCEPROP 2 LAST SIG_NAME FM_BOARD_SKU_ID2
J 0
(3800 1835);
DISPLAY 0.659574 (3800 1835);
PAINT WHITE (3800 1835);
WIRE 16 -1 (3575 1875)(4700 1875);
FORCEPROP 0 LAST CDS_PHYS_NET_NAME TP_GPP_M_8
J 0
(3800 1916);
PAINT MONO (3800 1916);
DISPLAY INVISIBLE (3800 1916);
FORCEPROP 2 LAST SIG_NAME FM_BOARD_SKU_ID3
J 0
(3800 1885);
DISPLAY 0.659574 (3800 1885);
PAINT WHITE (3800 1885);
WIRE 16 -1 (3575 1975)(4700 1975);
FORCEPROP 0 LAST CDS_PHYS_NET_NAME FM_PCIE_EDSFF4A_PRSNT_1_N
J 0
(3800 2016);
PAINT MONO (3800 2016);
DISPLAY INVISIBLE (3800 2016);
FORCEPROP 2 LAST SIG_NAME PD_GPP_M_8
J 0
(3800 1985);
DISPLAY 0.659574 (3800 1985);
PAINT WHITE (3800 1985);
WIRE 16 -1 (3575 2025)(4700 2025);
FORCEPROP 0 LAST CDS_PHYS_NET_NAME H_CPU0_PMSYNC_PCH_R
J 0
(3800 2066);
PAINT MONO (3800 2066);
DISPLAY INVISIBLE (3800 2066);
FORCEPROP 2 LAST SIG_NAME FM_PCH_BIOS_RCVR_MODE
J 0
(3800 2035);
DISPLAY 0.659574 (3800 2035);
PAINT WHITE (3800 2035);
WIRE 16 -1 (3575 2075)(4700 2075);
FORCEPROP 0 LAST CDS_PHYS_NET_NAME FM_PCIE_EDSFF4A_PRSNT_1_N
J 0
(3800 2116);
PAINT MONO (3800 2116);
DISPLAY INVISIBLE (3800 2116);
FORCEPROP 2 LAST SIG_NAME TP_GPP_M_12
J 0
(3800 2085);
DISPLAY 0.659574 (3800 2085);
PAINT WHITE (3800 2085);
WIRE 16 -1 (-2200 900)(-2200 1050);
WIRE 16 -1 (3575 2825)(4700 2825);
FORCEPROP 0 LAST CDS_PHYS_NET_NAME TP_PCH_GPP_L_8
J 0
(3725 2866);
PAINT MONO (3725 2866);
DISPLAY INVISIBLE (3725 2866);
FORCEPROP 2 LAST SIG_NAME FM_PCH_BMC_RST_R_N
J 0
(3800 2835);
DISPLAY 0.659574 (3800 2835);
PAINT WHITE (3800 2835);
WIRE 16 -1 (3575 2875)(4700 2875);
FORCEPROP 0 LAST CDS_PHYS_NET_NAME TP_PCH_GPP_L_8
J 0
(3725 2916);
PAINT MONO (3725 2916);
DISPLAY INVISIBLE (3725 2916);
FORCEPROP 2 LAST SIG_NAME PD_GPP_I_13
J 0
(3800 2885);
DISPLAY 0.659574 (3800 2885);
PAINT WHITE (3800 2885);
WIRE 16 -1 (3575 2925)(4700 2925);
FORCEPROP 0 LAST CDS_PHYS_NET_NAME TP_PCH_GPP_L_8
J 0
(3725 2966);
PAINT MONO (3725 2966);
DISPLAY INVISIBLE (3725 2966);
FORCEPROP 2 LAST SIG_NAME PD_GPP_I_14
J 0
(3800 2935);
DISPLAY 0.659574 (3800 2935);
PAINT WHITE (3800 2935);
WIRE 16 -1 (3575 2975)(4700 2975);
FORCEPROP 0 LAST CDS_PHYS_NET_NAME TP_PCH_GPP_L_8
J 0
(3725 3016);
PAINT MONO (3725 3016);
DISPLAY INVISIBLE (3725 3016);
FORCEPROP 2 LAST SIG_NAME PD_GPP_I_15
J 0
(3800 2985);
DISPLAY 0.659574 (3800 2985);
PAINT WHITE (3800 2985);
WIRE 16 -1 (3575 3025)(4700 3025);
FORCEPROP 0 LAST CDS_PHYS_NET_NAME TP_PCH_GPP_L_8
J 0
(3725 3066);
PAINT MONO (3725 3066);
DISPLAY INVISIBLE (3725 3066);
FORCEPROP 2 LAST SIG_NAME PD_GPP_I_16
J 0
(3800 3035);
DISPLAY 0.659574 (3800 3035);
PAINT WHITE (3800 3035);
WIRE 16 -1 (3575 3075)(4700 3075);
FORCEPROP 0 LAST CDS_PHYS_NET_NAME OCP_LFF_4CP_BIF0_N
J 0
(3725 3116);
PAINT MONO (3725 3116);
DISPLAY INVISIBLE (3725 3116);
FORCEPROP 2 LAST SIG_NAME PD_GPP_I_17
J 0
(3800 3085);
DISPLAY 0.659574 (3800 3085);
PAINT WHITE (3800 3085);
WIRE 16 -1 (3575 3125)(4700 3125);
FORCEPROP 0 LAST CDS_PHYS_NET_NAME H_CPU0_PMSYNC_PCH_R
J 0
(3725 3166);
PAINT MONO (3725 3166);
DISPLAY INVISIBLE (3725 3166);
FORCEPROP 2 LAST SIG_NAME IRQ_TPM_SPI_N
J 0
(3800 3135);
DISPLAY 0.659574 (3800 3135);
PAINT WHITE (3800 3135);
WIRE 16 -1 (3575 3175)(4700 3175);
FORCEPROP 0 LAST CDS_PHYS_NET_NAME H_CPU0_PMSYNC_PCH_R
J 0
(3725 3216);
PAINT MONO (3725 3216);
DISPLAY INVISIBLE (3725 3216);
FORCEPROP 2 LAST SIG_NAME FM_PCH_DFXTESTMODE
J 0
(3800 3185);
DISPLAY 0.659574 (3800 3185);
PAINT WHITE (3800 3185);
WIRE 16 -1 (3575 2725)(4700 2725);
FORCEPROP 0 LAST CDS_PHYS_NET_NAME RISER2_TYPE_ID1
J 0
(3800 2766);
PAINT MONO (3800 2766);
DISPLAY INVISIBLE (3800 2766);
FORCEPROP 2 LAST SIG_NAME TP_GPP_L_8
J 0
(3800 2735);
DISPLAY 0.659574 (3800 2735);
PAINT WHITE (3800 2735);
WIRE 16 -1 (3575 2675)(4700 2675);
FORCEPROP 0 LAST CDS_PHYS_NET_NAME RISER2_TYPE_ID1
J 0
(3800 2716);
PAINT MONO (3800 2716);
DISPLAY INVISIBLE (3800 2716);
FORCEPROP 2 LAST SIG_NAME TP_GPP_L_7
J 0
(3800 2685);
DISPLAY 0.659574 (3800 2685);
PAINT WHITE (3800 2685);
WIRE 16 -1 (3575 2325)(4700 2325);
FORCEPROP 2 LAST SIG_NAME H_CPU0_PMSYNC_PCH_R2
J 0
(3800 2335);
DISPLAY 0.659574 (3800 2335);
PAINT WHITE (3800 2335);
WIRE 16 -1 (3575 2425)(4700 2425);
FORCEPROP 0 LAST CDS_PHYS_NET_NAME RISER2_TYPE_ID1
J 0
(3800 2466);
PAINT MONO (3800 2466);
DISPLAY INVISIBLE (3800 2466);
FORCEPROP 2 LAST SIG_NAME TP_GPP_L_2
J 0
(3800 2435);
DISPLAY 0.659574 (3800 2435);
PAINT WHITE (3800 2435);
WIRE 16 -1 (3575 2575)(4700 2575);
FORCEPROP 2 LAST SIG_NAME FM_PASSWORD_CLEAR_N
J 0
(3800 2585);
DISPLAY 0.659574 (3800 2585);
PAINT WHITE (3800 2585);
WIRE 16 -1 (3575 2625)(4700 2625);
FORCEPROP 2 LAST SIG_NAME FM_MFG_MODE
J 0
(3800 2635);
DISPLAY 0.659574 (3800 2635);
PAINT WHITE (3800 2635);
WIRE 16 -1 (700 -375)(1825 -375);
FORCEPROP 0 LAST CDS_PHYS_NET_NAME FM_PCIE_EDSFF2B_PRSNT_1_N
J 0
(925 -334);
PAINT MONO (925 -334);
DISPLAY INVISIBLE (925 -334);
FORCEPROP 2 LAST SIG_NAME PD_PCH_GPP_E_10
J 0
(915 -365);
DISPLAY 0.531915 (915 -365);
PAINT WHITE (915 -365);
WIRE 16 -1 (700 -175)(1825 -175);
FORCEPROP 0 LAST CDS_PHYS_NET_NAME FM_PCH_SLP_S4_N
J 0
(725 -133);
PAINT MONO (725 -133);
DISPLAY INVISIBLE (725 -133);
FORCEPROP 0 LAST SIG_NAME PD_PCH_GPP_E_12
J 0
(915 -165);
DISPLAY 0.553191 (915 -165);
PAINT WHITE (915 -165);
WIRE 16 -1 (3575 1725)(4700 1725);
FORCEPROP 0 LAST CDS_PHYS_NET_NAME PCIE_RISER2_PRSNT2_N
J 0
(3800 1766);
PAINT MONO (3800 1766);
DISPLAY INVISIBLE (3800 1766);
FORCEPROP 2 LAST SIG_NAME FM_BOARD_SKU_ID0
J 0
(3800 1735);
DISPLAY 0.659574 (3800 1735);
PAINT WHITE (3800 1735);
WIRE 16 -1 (3575 1925)(4700 1925);
FORCEPROP 0 LAST CDS_PHYS_NET_NAME RISER2_TYPE_ID1
J 0
(3800 1966);
PAINT MONO (3800 1966);
DISPLAY INVISIBLE (3800 1966);
FORCEPROP 2 LAST SIG_NAME FM_BOARD_SKU_ID4
J 0
(3800 1935);
DISPLAY 0.659574 (3800 1935);
PAINT WHITE (3800 1935);
WIRE 16 -1 (3575 2525)(4700 2525);
FORCEPROP 2 LAST SIG_NAME FM_ME_RCVR_N
J 0
(3800 2535);
DISPLAY 0.659574 (3800 2535);
PAINT WHITE (3800 2535);
WIRE 16 -1 (3575 2475)(4700 2475);
FORCEPROP 2 LAST SIG_NAME FM_BIOS_ADV_FUNCTIONS
J 0
(3800 2485);
DISPLAY 0.659574 (3800 2485);
PAINT WHITE (3800 2485);
WIRE 16 -1 (3575 2375)(4700 2375);
FORCEPROP 2 LAST SIG_NAME H_CPU0_PMDOWN_PCH
J 0
(3800 2385);
DISPLAY 0.659574 (3800 2385);
PAINT WHITE (3800 2385);
WIRE 16 -1 (3575 3225)(4700 3225);
FORCEPROP 0 LAST CDS_PHYS_NET_NAME H_CPU0_PMSYNC_PCH_R
J 0
(3725 3266);
PAINT MONO (3725 3266);
DISPLAY INVISIBLE (3725 3266);
FORCEPROP 2 LAST SIG_NAME FM_PCH_XTALSEL
J 0
(3800 3235);
DISPLAY 0.659574 (3800 3235);
PAINT WHITE (3800 3235);
WIRE 16 -1 (1825 -275)(700 -275);
FORCEPROP 0 LAST CDS_PHYS_NET_NAME FM_PCIE_EDSFF4B_PRSNT_1_N
J 0
(925 -234);
PAINT MONO (925 -234);
DISPLAY INVISIBLE (925 -234);
FORCEPROP 2 LAST SIG_NAME PD_PCH_GPP_E_11
J 0
(915 -265);
DISPLAY 0.531915 (915 -265);
PAINT WHITE (915 -265);
WIRE 16 -1 (700 225)(1825 225);
FORCEPROP 0 LAST CDS_PHYS_NET_NAME TP_PCH_GPP_L_8
J 0
(850 266);
PAINT MONO (850 266);
DISPLAY INVISIBLE (850 266);
FORCEPROP 2 LAST SIG_NAME PD_GPP_I_16
J 0
(925 235);
DISPLAY 0.659574 (925 235);
PAINT WHITE (925 235);
WIRE 16 -1 (700 425)(1825 425);
FORCEPROP 0 LAST CDS_PHYS_NET_NAME FM_PCIE_EDSFF4A_PRSNT_1_N
J 0
(925 466);
PAINT MONO (925 466);
DISPLAY INVISIBLE (925 466);
FORCEPROP 2 LAST SIG_NAME PD_GPP_M_8
J 0
(925 435);
DISPLAY 0.659574 (925 435);
PAINT WHITE (925 435);
WIRE 16 -1 (700 25)(1825 25);
FORCEPROP 0 LAST CDS_PHYS_NET_NAME FM_PCH_SLP_S4_N
J 0
(725 67);
PAINT MONO (725 67);
DISPLAY INVISIBLE (725 67);
FORCEPROP 0 LAST SIG_NAME PD_PCH_GPP_E_14
J 0
(915 35);
DISPLAY 0.553191 (915 35);
PAINT WHITE (915 35);
WIRE 16 -1 (700 125)(1825 125);
FORCEPROP 0 LAST CDS_PHYS_NET_NAME TP_PCH_GPP_L_8
J 0
(850 166);
PAINT MONO (850 166);
DISPLAY INVISIBLE (850 166);
FORCEPROP 2 LAST SIG_NAME PD_GPP_I_15
J 0
(925 135);
DISPLAY 0.659574 (925 135);
PAINT WHITE (925 135);
WIRE 16 -1 (700 -75)(1825 -75);
FORCEPROP 0 LAST CDS_PHYS_NET_NAME TP_PCH_MGPIO_TEST1
J 0
(725 -33);
PAINT MONO (725 -33);
DISPLAY INVISIBLE (725 -33);
FORCEPROP 0 LAST SIG_NAME PD_PCH_GPP_E_13
J 0
(915 -65);
DISPLAY 0.553191 (915 -65);
PAINT WHITE (915 -65);
WIRE 16 -1 (700 -575)(1825 -575);
FORCEPROP 0 LAST CDS_PHYS_NET_NAME FM_EDSFF2_TYPE_ID
J 0
(725 -533);
PAINT MONO (725 -533);
DISPLAY INVISIBLE (725 -533);
FORCEPROP 0 LAST SIG_NAME PD_PCH_GPP_E_8
J 0
(915 -565);
DISPLAY 0.553191 (915 -565);
PAINT WHITE (915 -565);
WIRE 16 -1 (700 -475)(1825 -475);
FORCEPROP 0 LAST CDS_PHYS_NET_NAME FM_PCIE_EDSFF1B_PRSNT_1_N
J 0
(925 -434);
PAINT MONO (925 -434);
DISPLAY INVISIBLE (925 -434);
FORCEPROP 2 LAST SIG_NAME PD_PCH_GPP_E_9
J 0
(915 -465);
DISPLAY 0.531915 (915 -465);
PAINT WHITE (915 -465);
WIRE 16 -1 (700 -775)(1825 -775);
FORCEPROP 0 LAST CDS_PHYS_NET_NAME OCP_SFF_BIF2_N
J 0
(850 -734);
PAINT MONO (850 -734);
DISPLAY INVISIBLE (850 -734);
FORCEPROP 2 LAST SIG_NAME PD_GPP_I_14
J 0
(925 -765);
DISPLAY 0.659574 (925 -765);
PAINT WHITE (925 -765);
WIRE 16 -1 (700 -675)(1825 -675);
FORCEPROP 0 LAST CDS_PHYS_NET_NAME TP_EDSFF1A_TYPE_ID
J 0
(725 -633);
PAINT MONO (725 -633);
DISPLAY INVISIBLE (725 -633);
FORCEPROP 0 LAST SIG_NAME PD_PCH_GPP_E_3
J 0
(915 -665);
DISPLAY 0.553191 (915 -665);
PAINT WHITE (915 -665);
WIRE 16 -1 (-1075 -475)(-1550 -475);
WIRE 16 -1 (-1075 -475)(-1075 -600);
WIRE 16 -1 (-1075 -600)(-1075 -725);
WIRE 16 -1 (-1550 -475)(-2025 -475);
WIRE 16 -1 (-2025 -475)(-2500 -475);
WIRE 16 -1 (-1550 -475)(-1550 -600);
WIRE 16 -1 (-1550 -600)(-1075 -600);
WIRE 16 -1 (-2025 -600)(-1550 -600);
WIRE 16 -1 (-2025 -475)(-2025 -600);
WIRE 16 -1 (-1075 -725)(-1075 -850);
WIRE 16 -1 (-1550 -600)(-1550 -725);
WIRE 16 -1 (-1550 -725)(-1075 -725);
WIRE 16 -1 (-2500 -475)(-2500 -600);
WIRE 16 -1 (-2500 -600)(-2025 -600);
WIRE 16 -1 (-2500 -725)(-2500 -600);
WIRE 16 -1 (-1550 -725)(-1550 -850);
WIRE 16 -1 (-1550 -850)(-1075 -850);
WIRE 16 -1 (-2025 -600)(-2025 -725);
WIRE 16 -1 (-2025 -725)(-1550 -725);
WIRE 16 -1 (-2500 -725)(-2025 -725);
WIRE 16 -1 (-2025 -725)(-2025 -850);
WIRE 16 -1 (-2025 -850)(-1550 -850);
WIRE 16 -1 (-2500 -850)(-2500 -725);
WIRE 16 -1 (-2500 -850)(-2025 -850);
WIRE 16 -1 (-2200 450)(-2200 250);
WIRE 16 -1 (-2200 700)(-2200 450);
WIRE 16 -1 (-2200 450)(-850 450);
FORCEPROP 2 LAST SIG_NAME FM_M2_E1S_E6_PEDET
J 0
(-1760 460);
DISPLAY 0.808511 (-1760 460);
PAINT WHITE (-1760 460);
WIRE 16 -1 (-1900 1875)(-375 1875);
FORCEPROP 0 LAST CDS_PHYS_NET_NAME FM_PCH_SLP_S4_N
J 0
(-1875 1917);
PAINT MONO (-1875 1917);
DISPLAY INVISIBLE (-1875 1917);
FORCEPROP 0 LAST SIG_NAME FM_PCH_EXTERNALCLKMODE
J 0
(-1800 1885);
DISPLAY 0.680851 (-1800 1885);
PAINT WHITE (-1800 1885);
WIRE 16 -1 (3575 2125)(4700 2125);
FORCEPROP 0 LAST CDS_PHYS_NET_NAME FM_PCIE_EDSFF4A_PRSNT_1_N
J 0
(3800 2166);
PAINT MONO (3800 2166);
DISPLAY INVISIBLE (3800 2166);
FORCEPROP 2 LAST SIG_NAME PD_GPP_M_15
J 0
(3800 2135);
DISPLAY 0.659574 (3800 2135);
PAINT WHITE (3800 2135);
WIRE 16 -1 (3575 2175)(4700 2175);
FORCEPROP 0 LAST CDS_PHYS_NET_NAME RISER2_TYPE_ID1
J 0
(3800 2216);
PAINT MONO (3800 2216);
DISPLAY INVISIBLE (3800 2216);
FORCEPROP 2 LAST SIG_NAME PD_GPP_M_16
J 0
(3800 2185);
DISPLAY 0.659574 (3800 2185);
PAINT WHITE (3800 2185);
WIRE 16 -1 (3575 2225)(4700 2225);
FORCEPROP 0 LAST CDS_PHYS_NET_NAME RISER2_TYPE_ID1
J 0
(3800 2266);
PAINT MONO (3800 2266);
DISPLAY INVISIBLE (3800 2266);
FORCEPROP 2 LAST SIG_NAME PD_GPP_M_17
J 0
(3800 2235);
DISPLAY 0.659574 (3800 2235);
PAINT WHITE (3800 2235);
WIRE 16 -1 (-1900 1825)(-375 1825);
FORCEPROP 0 LAST CDS_PHYS_NET_NAME FM_PCH_SLP_S4_N
J 0
(-1875 1867);
PAINT MONO (-1875 1867);
DISPLAY INVISIBLE (-1875 1867);
FORCEPROP 0 LAST SIG_NAME FM_PCH_IO_EXPANDER
J 0
(-1800 1835);
DISPLAY 0.680851 (-1800 1835);
PAINT WHITE (-1800 1835);
WIRE 16 -1 (-1900 1775)(-375 1775);
FORCEPROP 0 LAST CDS_PHYS_NET_NAME FM_PCH_SLP_S4_N
J 0
(-1875 1817);
PAINT MONO (-1875 1817);
DISPLAY INVISIBLE (-1875 1817);
FORCEPROP 0 LAST SIG_NAME FM_PCH_VISA_DEFAULT
J 0
(-1800 1785);
DISPLAY 0.680851 (-1800 1785);
PAINT WHITE (-1800 1785);
WIRE 16 -1 (-1900 2325)(-375 2325);
FORCEPROP 0 LAST CDS_PHYS_NET_NAME FM_PCH_SLP_S4_N
J 0
(-1875 2367);
PAINT MONO (-1875 2367);
DISPLAY INVISIBLE (-1875 2367);
FORCEPROP 0 LAST SIG_NAME TP_PCH_GPP_E_1
J 0
(-1800 2335);
DISPLAY 0.680851 (-1800 2335);
PAINT WHITE (-1800 2335);
WIRE 16 -1 (-1900 2275)(-375 2275);
FORCEPROP 0 LAST CDS_PHYS_NET_NAME FM_PCH_SLP_S4_N
J 0
(-1875 2317);
PAINT MONO (-1875 2317);
DISPLAY INVISIBLE (-1875 2317);
FORCEPROP 0 LAST SIG_NAME TP_PCH_GPP_E_0
J 0
(-1800 2285);
DISPLAY 0.680851 (-1800 2285);
PAINT WHITE (-1800 2285);
WIRE 16 -1 (-1900 2175)(-375 2175);
FORCEPROP 0 LAST CDS_PHYS_NET_NAME FM_PCH_SLP_S4_N
J 0
(-1875 2217);
PAINT MONO (-1875 2217);
DISPLAY INVISIBLE (-1875 2217);
FORCEPROP 0 LAST SIG_NAME FM_LT_KEY_DOWNGRADE_N
J 0
(-1800 2185);
DISPLAY 0.680851 (-1800 2185);
PAINT WHITE (-1800 2185);
WIRE 16 -1 (-1900 2075)(-375 2075);
FORCEPROP 0 LAST CDS_PHYS_NET_NAME FM_PCH_SLP_S4_N
J 0
(-1875 2117);
PAINT MONO (-1875 2117);
DISPLAY INVISIBLE (-1875 2117);
FORCEPROP 0 LAST SIG_NAME FM_PCH_XTAL_INPUT_MODE_MGPIO_TEST3
J 0
(-1800 2085);
DISPLAY 0.680851 (-1800 2085);
PAINT WHITE (-1800 2085);
WIRE 16 -1 (-1900 2975)(-375 2975);
FORCEPROP 0 LAST CDS_PHYS_NET_NAME FM_PCH_SLP_S4_N
J 0
(-1875 3017);
PAINT MONO (-1875 3017);
DISPLAY INVISIBLE (-1875 3017);
FORCEPROP 0 LAST SIG_NAME PD_PCH_GPP_E_14
J 0
(-1800 2985);
DISPLAY 0.680851 (-1800 2985);
PAINT WHITE (-1800 2985);
WIRE 16 -1 (-1900 2875)(-375 2875);
FORCEPROP 0 LAST CDS_PHYS_NET_NAME FM_PCH_SLP_S4_N
J 0
(-1875 2917);
PAINT MONO (-1875 2917);
DISPLAY INVISIBLE (-1875 2917);
FORCEPROP 0 LAST SIG_NAME PD_PCH_GPP_E_12
J 0
(-1800 2885);
DISPLAY 0.680851 (-1800 2885);
PAINT WHITE (-1800 2885);
WIRE 16 -1 (-375 2825)(-1900 2825);
FORCEPROP 0 LAST CDS_PHYS_NET_NAME FM_PCIE_EDSFF4B_PRSNT_1_N
J 0
(-1675 2866);
PAINT MONO (-1675 2866);
DISPLAY INVISIBLE (-1675 2866);
FORCEPROP 2 LAST SIG_NAME PD_PCH_GPP_E_11
J 0
(-1800 2835);
DISPLAY 0.659574 (-1800 2835);
PAINT WHITE (-1800 2835);
WIRE 16 -1 (-1900 2775)(-375 2775);
FORCEPROP 0 LAST CDS_PHYS_NET_NAME FM_PCIE_EDSFF2B_PRSNT_1_N
J 0
(-1675 2816);
PAINT MONO (-1675 2816);
DISPLAY INVISIBLE (-1675 2816);
FORCEPROP 2 LAST SIG_NAME PD_PCH_GPP_E_10
J 0
(-1800 2785);
DISPLAY 0.659574 (-1800 2785);
PAINT WHITE (-1800 2785);
WIRE 16 -1 (-1900 2725)(-375 2725);
FORCEPROP 0 LAST CDS_PHYS_NET_NAME FM_PCIE_EDSFF1B_PRSNT_1_N
J 0
(-1675 2766);
PAINT MONO (-1675 2766);
DISPLAY INVISIBLE (-1675 2766);
FORCEPROP 2 LAST SIG_NAME PD_PCH_GPP_E_9
J 0
(-1800 2735);
DISPLAY 0.659574 (-1800 2735);
PAINT WHITE (-1800 2735);
WIRE 16 -1 (-1900 2675)(-375 2675);
FORCEPROP 0 LAST CDS_PHYS_NET_NAME FM_EDSFF2_TYPE_ID
J 0
(-1875 2717);
PAINT MONO (-1875 2717);
DISPLAY INVISIBLE (-1875 2717);
FORCEPROP 0 LAST SIG_NAME PD_PCH_GPP_E_8
J 0
(-1800 2685);
DISPLAY 0.680851 (-1800 2685);
PAINT WHITE (-1800 2685);
WIRE 16 -1 (-1900 2625)(-375 2625);
FORCEPROP 0 LAST CDS_PHYS_NET_NAME FM_PCH_SLP_S4_N
J 0
(-1875 2667);
PAINT MONO (-1875 2667);
DISPLAY INVISIBLE (-1875 2667);
FORCEPROP 0 LAST SIG_NAME FM_M2_SSD0_E7_PEDET
J 0
(-1800 2635);
DISPLAY 0.680851 (-1800 2635);
PAINT WHITE (-1800 2635);
WIRE 16 -1 (-1900 2925)(-375 2925);
FORCEPROP 0 LAST CDS_PHYS_NET_NAME TP_PCH_MGPIO_TEST1
J 0
(-1875 2967);
PAINT MONO (-1875 2967);
DISPLAY INVISIBLE (-1875 2967);
FORCEPROP 0 LAST SIG_NAME PD_PCH_GPP_E_13
J 0
(-1800 2935);
DISPLAY 0.680851 (-1800 2935);
PAINT WHITE (-1800 2935);
WIRE 16 -1 (-1900 3025)(-375 3025);
FORCEPROP 0 LAST CDS_PHYS_NET_NAME FM_PCH_SLP_S4_N
J 0
(-1875 3067);
PAINT MONO (-1875 3067);
DISPLAY INVISIBLE (-1875 3067);
FORCEPROP 0 LAST SIG_NAME FM_ME_AUTHN_FAIL
J 0
(-1800 3035);
DISPLAY 0.680851 (-1800 3035);
PAINT WHITE (-1800 3035);
WIRE 16 -1 (-1900 2375)(-375 2375);
FORCEPROP 0 LAST CDS_PHYS_NET_NAME TP_EDSFF1A_TYPE_ID
J 0
(-1875 2417);
PAINT MONO (-1875 2417);
DISPLAY INVISIBLE (-1875 2417);
FORCEPROP 0 LAST SIG_NAME TP_PCH_GPP_E_2
J 0
(-1800 2385);
DISPLAY 0.680851 (-1800 2385);
PAINT WHITE (-1800 2385);
WIRE 16 -1 (-1900 2425)(-375 2425);
FORCEPROP 0 LAST CDS_PHYS_NET_NAME TP_EDSFF1A_TYPE_ID
J 0
(-1875 2467);
PAINT MONO (-1875 2467);
DISPLAY INVISIBLE (-1875 2467);
FORCEPROP 0 LAST SIG_NAME PD_PCH_GPP_E_3
J 0
(-1800 2435);
DISPLAY 0.680851 (-1800 2435);
PAINT WHITE (-1800 2435);
WIRE 16 -1 (-1900 2475)(-375 2475);
FORCEPROP 0 LAST CDS_PHYS_NET_NAME FM_PCH_SLP_S4_N
J 0
(-1875 2517);
PAINT MONO (-1875 2517);
DISPLAY INVISIBLE (-1875 2517);
FORCEPROP 0 LAST SIG_NAME TP_EDSFF1A_TYPE_ID
J 0
(-1800 2485);
DISPLAY 0.680851 (-1800 2485);
PAINT WHITE (-1800 2485);
WIRE 16 -1 (-1900 2525)(-375 2525);
FORCEPROP 0 LAST CDS_PHYS_NET_NAME FM_EDSFF1_TYPE_ID
J 0
(-1875 2567);
PAINT MONO (-1875 2567);
DISPLAY INVISIBLE (-1875 2567);
FORCEPROP 0 LAST SIG_NAME TP_EDSFF1B_TYPE_ID
J 0
(-1800 2535);
DISPLAY 0.680851 (-1800 2535);
PAINT WHITE (-1800 2535);
WIRE 16 -1 (-2475 525)(-2475 250);
WIRE 16 -1 (-2475 700)(-2475 525);
WIRE 16 -1 (-2475 525)(-850 525);
FORCEPROP 2 LAST SIG_NAME FM_M2_SSD0_E7_PEDET
J 0
(-1760 535);
DISPLAY 0.808511 (-1760 535);
PAINT WHITE (-1760 535);
WIRE 16 -1 (-1900 1975)(-375 1975);
FORCEPROP 0 LAST CDS_PHYS_NET_NAME FM_PCH_SLP_S4_N
J 0
(-1875 2017);
PAINT MONO (-1875 2017);
DISPLAY INVISIBLE (-1875 2017);
FORCEPROP 0 LAST SIG_NAME TP_PCH_MGPIO_TEST1
J 0
(-1800 1985);
DISPLAY 0.680851 (-1800 1985);
PAINT WHITE (-1800 1985);
WIRE 16 -1 (-1900 2125)(-375 2125);
FORCEPROP 0 LAST CDS_PHYS_NET_NAME FM_PCH_SLP_S4_N
J 0
(-1875 2167);
PAINT MONO (-1875 2167);
DISPLAY INVISIBLE (-1875 2167);
FORCEPROP 0 LAST SIG_NAME PU_PCH_PMCALERT_N
J 0
(-1800 2135);
DISPLAY 0.680851 (-1800 2135);
PAINT WHITE (-1800 2135);
WIRE 16 -1 (-1900 2575)(-375 2575);
FORCEPROP 0 LAST CDS_PHYS_NET_NAME FM_PCH_SLP_S4_N
J 0
(-1875 2617);
PAINT MONO (-1875 2617);
DISPLAY INVISIBLE (-1875 2617);
FORCEPROP 0 LAST SIG_NAME FM_M2_E1S_E6_PEDET
J 0
(-1800 2585);
DISPLAY 0.680851 (-1800 2585);
PAINT WHITE (-1800 2585);
WIRE 16 -1 (-1900 3075)(-375 3075);
FORCEPROP 0 LAST CDS_PHYS_NET_NAME FM_PCH_SLP_S4_N
J 0
(-1875 3117);
PAINT MONO (-1875 3117);
DISPLAY INVISIBLE (-1875 3117);
FORCEPROP 0 LAST SIG_NAME FM_ME_BT_DONE
J 0
(-1800 3085);
DISPLAY 0.680851 (-1800 3085);
PAINT WHITE (-1800 3085);
WIRE 16 -1 (-1900 3125)(-375 3125);
FORCEPROP 0 LAST CDS_PHYS_NET_NAME FM_PCH_SLP_S4_N
J 0
(-1875 3167);
PAINT MONO (-1875 3167);
DISPLAY INVISIBLE (-1875 3167);
FORCEPROP 0 LAST SIG_NAME FM_DEBUG_PORT_PRSNT_R_N
J 0
(-1800 3135);
DISPLAY 0.680851 (-1800 3135);
PAINT WHITE (-1800 3135);
WIRE 16 -1 (-1900 3225)(-375 3225);
FORCEPROP 0 LAST CDS_PHYS_NET_NAME FM_PCH_SLP_S4_N
J 0
(-1875 3267);
PAINT MONO (-1875 3267);
DISPLAY INVISIBLE (-1875 3267);
FORCEPROP 0 LAST SIG_NAME FM_TPM_PRSNT_N
J 0
(-1800 3235);
DISPLAY 0.680851 (-1800 3235);
PAINT WHITE (-1800 3235);
WIRE 16 -1 (-1900 2025)(-375 2025);
FORCEPROP 0 LAST CDS_PHYS_NET_NAME FM_PCH_SLP_S4_N
J 0
(-1875 2067);
PAINT MONO (-1875 2067);
DISPLAY INVISIBLE (-1875 2067);
FORCEPROP 0 LAST SIG_NAME FM_PCH_RING_OSC_BYPASS_MGPIO_TEST2
J 0
(-1800 2035);
DISPLAY 0.680851 (-1800 2035);
PAINT WHITE (-1800 2035);
WIRE 16 -1 (-1900 1925)(-375 1925);
FORCEPROP 0 LAST CDS_PHYS_NET_NAME FM_PCH_SLP_S4_N
J 0
(-1875 1967);
PAINT MONO (-1875 1967);
DISPLAY INVISIBLE (-1875 1967);
FORCEPROP 0 LAST SIG_NAME FM_PCH_MCRO_LDO
J 0
(-1800 1935);
DISPLAY 0.680851 (-1800 1935);
PAINT WHITE (-1800 1935);
WIRE 16 -1 (-1900 3175)(-375 3175);
FORCEPROP 0 LAST CDS_PHYS_NET_NAME FM_PCH_SLP_S4_N
J 0
(-1875 3217);
PAINT MONO (-1875 3217);
DISPLAY INVISIBLE (-1875 3217);
FORCEPROP 0 LAST SIG_NAME FM_PS_PWROK_DLY_R_SEL
J 0
(-1800 3185);
DISPLAY 0.680851 (-1800 3185);
PAINT WHITE (-1800 3185);
DOT 1 (2450 625);
DOT 1 (2450 -175);
DOT 1 (2450 525);
DOT 1 (2450 325);
DOT 1 (2450 425);
DOT 1 (2450 225);
DOT 1 (2450 125);
DOT 1 (2450 25);
DOT 1 (2450 -275);
DOT 1 (2450 -375);
DOT 1 (2450 -475);
DOT 1 (2450 -575);
DOT 1 (2450 -675);
DOT 1 (2450 -775);
DOT 1 (2450 -875);
DOT 1 (-1550 -850);
DOT 1 (-2025 -850);
DOT 1 (-2500 -725);
DOT 1 (-1075 -600);
DOT 1 (-1075 -725);
DOT 1 (-1550 -600);
DOT 1 (-1550 -725);
DOT 1 (-2025 -600);
DOT 1 (-2025 -475);
DOT 1 (-2500 -600);
DOT 1 (-2025 -725);
DOT 1 (-2475 1050);
DOT 1 (-2475 525);
DOT 1 (-2200 450);
DOT 1 (-1550 -475);
DOT 1 (2450 -75);
FORCENOTE
20220801 ADD R4722 10K OHM PU
(3650 300) 0;
DISPLAY LEFT (3650 300);
DISPLAY 1.276596 (3650 300);
PAINT PINK (3650 300);
FORCENOTE
GPP_E_6
(-1475 -575) 0;
DISPLAY LEFT (-1475 -575);
DISPLAY 1.021277 (-1475 -575);
PAINT WHITE (-1475 -575);
FORCENOTE
GPP_E_7
(-1950 -575) 0;
DISPLAY LEFT (-1950 -575);
DISPLAY 1.021277 (-1950 -575);
PAINT WHITE (-1950 -575);
FORCENOTE
 0
(-1850 -700) 0;
DISPLAY LEFT (-1850 -700);
DISPLAY 1.021277 (-1850 -700);
PAINT WHITE (-1850 -700);
FORCENOTE
 1
(-1850 -825) 0;
DISPLAY LEFT (-1850 -825);
DISPLAY 1.021277 (-1850 -825);
PAINT WHITE (-1850 -825);
FORCENOTE
20210602 MODIFY FOR GT
(575 4250) 0;
DISPLAY LEFT (575 4250);
DISPLAY 1.595745 (575 4250);
PAINT PINK (575 4250);
FORCENOTE
CONFIG
(-2400 -575) 0;
DISPLAY LEFT (-2400 -575);
DISPLAY 1.021277 (-2400 -575);
PAINT WHITE (-2400 -575);
FORCENOTE
SATA
(-2375 -700) 0;
DISPLAY LEFT (-2375 -700);
DISPLAY 1.021277 (-2375 -700);
PAINT WHITE (-2375 -700);
FORCENOTE
 0
(-1375 -700) 0;
DISPLAY LEFT (-1375 -700);
DISPLAY 1.021277 (-1375 -700);
PAINT WHITE (-1375 -700);
FORCENOTE
 1
(-1375 -825) 0;
DISPLAY LEFT (-1375 -825);
DISPLAY 1.021277 (-1375 -825);
PAINT WHITE (-1375 -825);
FORCENOTE
PCIE
(-2375 -825) 0;
DISPLAY LEFT (-2375 -825);
DISPLAY 1.021277 (-2375 -825);
PAINT WHITE (-2375 -825);
FORCENOTE
20211130 ADD 10K OHM PD
(800 -1175) 0;
DISPLAY LEFT (800 -1175);
DISPLAY 1.276596 (800 -1175);
PAINT PINK (800 -1175);
QUIT
